FILE_TYPE = MACRO_DRAWING;
SET COLOR_WIRE YELLOW;
SET COLOR_PROP ORANGE;
SET COLOR_DOT WHITE;
SET COLOR_ARC YELLOW;
SET COLOR_BODY GREEN;
SET COLOR_NOTE PURPLE;
SET PROP_DISPLAY VALUE;
SET PAGE_NUMBER P25;
FORCEADD GENOA_SP5..17
(-5025 5075);
FORCEPROP 1 LAST LOCATION U25
J 0
(-5620 6331);
DISPLAY 0.489362 (-5620 6331);
PAINT SKYBLUE (-5620 6331);
FORCEPROP 0 LAST $SEC 17
J 0
(-5600 6375);
DISPLAY 0.680851 (-5600 6375);
PAINT MONO (-5600 6375);
DISPLAY INVISIBLE (-5600 6375);
FORCEPROP 0 LAST CDS_SEC 17
J 0
(-5625 6250);
DISPLAY 1.021277 (-5625 6250);
DISPLAY INVISIBLE (-5625 6250);
FORCEPROP 0 LASTPIN (-5775 5825) $PN CM36
J 2
(-5785 5835);
DISPLAY 0.489362 (-5785 5835);
PAINT MONO (-5785 5835);
FORCEPROP 0 LASTPIN (-5775 5725) $PN CP36
J 2
(-5785 5735);
DISPLAY 0.489362 (-5785 5735);
PAINT MONO (-5785 5735);
FORCEPROP 0 LASTPIN (-5775 5625) $PN CT36
J 2
(-5785 5635);
DISPLAY 0.489362 (-5785 5635);
PAINT MONO (-5785 5635);
FORCEPROP 0 LASTPIN (-5775 5525) $PN CN33
J 2
(-5785 5535);
DISPLAY 0.489362 (-5785 5535);
PAINT MONO (-5785 5535);
FORCEPROP 0 LASTPIN (-5775 5425) $PN CU33
J 2
(-5785 5435);
DISPLAY 0.489362 (-5785 5435);
PAINT MONO (-5785 5435);
FORCEPROP 0 LASTPIN (-5775 5325) $PN CR33
J 2
(-5785 5335);
DISPLAY 0.489362 (-5785 5335);
PAINT MONO (-5785 5335);
FORCEPROP 0 LASTPIN (-5775 5225) $PN CN30
J 2
(-5785 5235);
DISPLAY 0.489362 (-5785 5235);
PAINT MONO (-5785 5235);
FORCEPROP 0 LASTPIN (-5775 5125) $PN CU30
J 2
(-5785 5135);
DISPLAY 0.489362 (-5785 5135);
PAINT MONO (-5785 5135);
FORCEPROP 0 LASTPIN (-5775 5025) $PN CR30
J 2
(-5785 5035);
DISPLAY 0.489362 (-5785 5035);
PAINT MONO (-5785 5035);
FORCEPROP 0 LASTPIN (-5775 4925) $PN CL27
J 2
(-5785 4935);
DISPLAY 0.489362 (-5785 4935);
PAINT MONO (-5785 4935);
FORCEPROP 0 LASTPIN (-5775 4825) $PN CU27
J 2
(-5785 4835);
DISPLAY 0.489362 (-5785 4835);
PAINT MONO (-5785 4835);
FORCEPROP 0 LASTPIN (-5775 4725) $PN CR27
J 2
(-5785 4735);
DISPLAY 0.489362 (-5785 4735);
PAINT MONO (-5785 4735);
FORCEPROP 0 LASTPIN (-5775 4625) $PN CN27
J 2
(-5785 4635);
DISPLAY 0.489362 (-5785 4635);
PAINT MONO (-5785 4635);
FORCEPROP 0 LASTPIN (-5775 4525) $PN CL24
J 2
(-5785 4535);
DISPLAY 0.489362 (-5785 4535);
PAINT MONO (-5785 4535);
FORCEPROP 0 LASTPIN (-5775 4425) $PN CR24
J 2
(-5785 4435);
DISPLAY 0.489362 (-5785 4435);
PAINT MONO (-5785 4435);
FORCEPROP 0 LASTPIN (-5775 4325) $PN CN24
J 2
(-5785 4335);
DISPLAY 0.489362 (-5785 4335);
PAINT MONO (-5785 4335);
FORCEPROP 0 LASTPIN (-5775 5875) $PN CM35
J 2
(-5785 5885);
DISPLAY 0.489362 (-5785 5885);
PAINT MONO (-5785 5885);
FORCEPROP 0 LASTPIN (-5775 5775) $PN CP35
J 2
(-5785 5785);
DISPLAY 0.489362 (-5785 5785);
PAINT MONO (-5785 5785);
FORCEPROP 0 LASTPIN (-5775 5675) $PN CT35
J 2
(-5785 5685);
DISPLAY 0.489362 (-5785 5685);
PAINT MONO (-5785 5685);
FORCEPROP 0 LASTPIN (-5775 5575) $PN CN32
J 2
(-5785 5585);
DISPLAY 0.489362 (-5785 5585);
PAINT MONO (-5785 5585);
FORCEPROP 0 LASTPIN (-5775 5475) $PN CU32
J 2
(-5785 5485);
DISPLAY 0.489362 (-5785 5485);
PAINT MONO (-5785 5485);
FORCEPROP 0 LASTPIN (-5775 5375) $PN CR32
J 2
(-5785 5385);
DISPLAY 0.489362 (-5785 5385);
PAINT MONO (-5785 5385);
FORCEPROP 0 LASTPIN (-5775 5275) $PN CN29
J 2
(-5785 5285);
DISPLAY 0.489362 (-5785 5285);
PAINT MONO (-5785 5285);
FORCEPROP 0 LASTPIN (-5775 5175) $PN CU29
J 2
(-5785 5185);
DISPLAY 0.489362 (-5785 5185);
PAINT MONO (-5785 5185);
FORCEPROP 0 LASTPIN (-5775 5075) $PN CR29
J 2
(-5785 5085);
DISPLAY 0.489362 (-5785 5085);
PAINT MONO (-5785 5085);
FORCEPROP 0 LASTPIN (-5775 4975) $PN CL26
J 2
(-5785 4985);
DISPLAY 0.489362 (-5785 4985);
PAINT MONO (-5785 4985);
FORCEPROP 0 LASTPIN (-5775 4875) $PN CU26
J 2
(-5785 4885);
DISPLAY 0.489362 (-5785 4885);
PAINT MONO (-5785 4885);
FORCEPROP 0 LASTPIN (-5775 4775) $PN CR26
J 2
(-5785 4785);
DISPLAY 0.489362 (-5785 4785);
PAINT MONO (-5785 4785);
FORCEPROP 0 LASTPIN (-5775 4675) $PN CN26
J 2
(-5785 4685);
DISPLAY 0.489362 (-5785 4685);
PAINT MONO (-5785 4685);
FORCEPROP 0 LASTPIN (-5775 4575) $PN CL23
J 2
(-5785 4585);
DISPLAY 0.489362 (-5785 4585);
PAINT MONO (-5785 4585);
FORCEPROP 0 LASTPIN (-5775 4475) $PN CR23
J 2
(-5785 4485);
DISPLAY 0.489362 (-5785 4485);
PAINT MONO (-5785 4485);
FORCEPROP 0 LASTPIN (-5775 4375) $PN CN23
J 2
(-5785 4385);
DISPLAY 0.489362 (-5785 4385);
PAINT MONO (-5785 4385);
FORCEPROP 0 LASTPIN (-4275 5825) $PN BT35
J 0
(-4265 5835);
DISPLAY 0.489362 (-4265 5835);
PAINT MONO (-4265 5835);
FORCEPROP 0 LASTPIN (-4275 5725) $PN BV35
J 0
(-4265 5735);
DISPLAY 0.489362 (-4265 5735);
PAINT MONO (-4265 5735);
FORCEPROP 0 LASTPIN (-4275 5625) $PN CB35
J 0
(-4265 5635);
DISPLAY 0.489362 (-4265 5635);
PAINT MONO (-4265 5635);
FORCEPROP 0 LASTPIN (-4275 5525) $PN BY35
J 0
(-4265 5535);
DISPLAY 0.489362 (-4265 5535);
PAINT MONO (-4265 5535);
FORCEPROP 0 LASTPIN (-4275 5425) $PN BU32
J 0
(-4265 5435);
DISPLAY 0.489362 (-4265 5435);
PAINT MONO (-4265 5435);
FORCEPROP 0 LASTPIN (-4275 5325) $PN CA32
J 0
(-4265 5335);
DISPLAY 0.489362 (-4265 5335);
PAINT MONO (-4265 5335);
FORCEPROP 0 LASTPIN (-4275 5225) $PN BW32
J 0
(-4265 5235);
DISPLAY 0.489362 (-4265 5235);
PAINT MONO (-4265 5235);
FORCEPROP 0 LASTPIN (-4275 5125) $PN BU29
J 0
(-4265 5135);
DISPLAY 0.489362 (-4265 5135);
PAINT MONO (-4265 5135);
FORCEPROP 0 LASTPIN (-4275 5025) $PN CA29
J 0
(-4265 5035);
DISPLAY 0.489362 (-4265 5035);
PAINT MONO (-4265 5035);
FORCEPROP 0 LASTPIN (-4275 4925) $PN BW29
J 0
(-4265 4935);
DISPLAY 0.489362 (-4265 4935);
PAINT MONO (-4265 4935);
FORCEPROP 0 LASTPIN (-4275 4825) $PN BU26
J 0
(-4265 4835);
DISPLAY 0.489362 (-4265 4835);
PAINT MONO (-4265 4835);
FORCEPROP 0 LASTPIN (-4275 4725) $PN CA26
J 0
(-4265 4735);
DISPLAY 0.489362 (-4265 4735);
PAINT MONO (-4265 4735);
FORCEPROP 0 LASTPIN (-4275 4625) $PN BW26
J 0
(-4265 4635);
DISPLAY 0.489362 (-4265 4635);
PAINT MONO (-4265 4635);
FORCEPROP 0 LASTPIN (-4275 4525) $PN BU23
J 0
(-4265 4535);
DISPLAY 0.489362 (-4265 4535);
PAINT MONO (-4265 4535);
FORCEPROP 0 LASTPIN (-4275 4425) $PN CA23
J 0
(-4265 4435);
DISPLAY 0.489362 (-4265 4435);
PAINT MONO (-4265 4435);
FORCEPROP 0 LASTPIN (-4275 4325) $PN BW23
J 0
(-4265 4335);
DISPLAY 0.489362 (-4265 4335);
PAINT MONO (-4265 4335);
FORCEPROP 0 LASTPIN (-4275 5875) $PN BT36
J 0
(-4265 5885);
DISPLAY 0.489362 (-4265 5885);
PAINT MONO (-4265 5885);
FORCEPROP 0 LASTPIN (-4275 5775) $PN BV36
J 0
(-4265 5785);
DISPLAY 0.489362 (-4265 5785);
PAINT MONO (-4265 5785);
FORCEPROP 0 LASTPIN (-4275 5675) $PN CB36
J 0
(-4265 5685);
DISPLAY 0.489362 (-4265 5685);
PAINT MONO (-4265 5685);
FORCEPROP 0 LASTPIN (-4275 5575) $PN BY36
J 0
(-4265 5585);
DISPLAY 0.489362 (-4265 5585);
PAINT MONO (-4265 5585);
FORCEPROP 0 LASTPIN (-4275 5475) $PN BU33
J 0
(-4265 5485);
DISPLAY 0.489362 (-4265 5485);
PAINT MONO (-4265 5485);
FORCEPROP 0 LASTPIN (-4275 5375) $PN CA33
J 0
(-4265 5385);
DISPLAY 0.489362 (-4265 5385);
PAINT MONO (-4265 5385);
FORCEPROP 0 LASTPIN (-4275 5275) $PN BW33
J 0
(-4265 5285);
DISPLAY 0.489362 (-4265 5285);
PAINT MONO (-4265 5285);
FORCEPROP 0 LASTPIN (-4275 5175) $PN BU30
J 0
(-4265 5185);
DISPLAY 0.489362 (-4265 5185);
PAINT MONO (-4265 5185);
FORCEPROP 0 LASTPIN (-4275 5075) $PN CA30
J 0
(-4265 5085);
DISPLAY 0.489362 (-4265 5085);
PAINT MONO (-4265 5085);
FORCEPROP 0 LASTPIN (-4275 4975) $PN BW30
J 0
(-4265 4985);
DISPLAY 0.489362 (-4265 4985);
PAINT MONO (-4265 4985);
FORCEPROP 0 LASTPIN (-4275 4875) $PN BU27
J 0
(-4265 4885);
DISPLAY 0.489362 (-4265 4885);
PAINT MONO (-4265 4885);
FORCEPROP 0 LASTPIN (-4275 4775) $PN CA27
J 0
(-4265 4785);
DISPLAY 0.489362 (-4265 4785);
PAINT MONO (-4265 4785);
FORCEPROP 0 LASTPIN (-4275 4675) $PN BW27
J 0
(-4265 4685);
DISPLAY 0.489362 (-4265 4685);
PAINT MONO (-4265 4685);
FORCEPROP 0 LASTPIN (-4275 4575) $PN BU24
J 0
(-4265 4585);
DISPLAY 0.489362 (-4265 4585);
PAINT MONO (-4265 4585);
FORCEPROP 0 LASTPIN (-4275 4475) $PN CA24
J 0
(-4265 4485);
DISPLAY 0.489362 (-4265 4485);
PAINT MONO (-4265 4485);
FORCEPROP 0 LASTPIN (-4275 4375) $PN BW24
J 0
(-4265 4385);
DISPLAY 0.489362 (-4265 4385);
PAINT MONO (-4265 4385);
FORCEPROP 2 LAST VALUE SOCKET6096_13568-001
J 0
(-5625 6100);
DISPLAY 0.489362 (-5625 6100);
PAINT SKYBLUE (-5625 6100);
FORCEPROP 1 LAST MATERIAL IO
J 0
(-5620 6057);
DISPLAY 0.489362 (-5620 6057);
PAINT SKYBLUE (-5620 6057);
FORCEPROP 2 LAST PART_TYPE SMLF
J 0
(-5625 6150);
DISPLAY 1.021277 (-5625 6150);
FORCEPROP 1 LAST CDS_LMAN_SYM_OUTLINE -600,950,600,-950
J 0
(-5025 5075);
DISPLAY 0.468085 (-5025 5075);
PAINT GREEN (-5025 5075);
DISPLAY INVISIBLE (-5025 5075);
FORCEPROP 1 LAST NEEDS_NO_SIZE TRUE
J 0
(-5025 5075);
DISPLAY 0.723404 (-5025 5075);
PAINT GREEN (-5025 5075);
DISPLAY INVISIBLE (-5025 5075);
FORCEPROP 2 LAST CDS_LIB pure_quanta
J 0
(-5025 5075);
DISPLAY INVISIBLE (-5025 5075);
FORCEPROP 1 LAST PATH I147
J 0
(-5025 5075);
DISPLAY 0.723404 (-5025 5075);
PAINT GREEN (-5025 5075);
DISPLAY INVISIBLE (-5025 5075);
FORCEPROP 1 LAST PART_NUMBER DGA^6000030
J 0
(-5625 6250);
DISPLAY 0.489362 (-5625 6250);
PAINT SKYBLUE (-5625 6250);
DISPLAY INVISIBLE (-5625 6250);
FORCEADD GENOA_SP5..18
(-5025 2250);
FORCEPROP 1 LAST LOCATION U25
J 0
(-5600 3450);
DISPLAY 0.489362 (-5600 3450);
PAINT SKYBLUE (-5600 3450);
FORCEPROP 0 LAST $SEC 18
J 0
(-5600 3550);
DISPLAY 0.680851 (-5600 3550);
PAINT MONO (-5600 3550);
DISPLAY INVISIBLE (-5600 3550);
FORCEPROP 0 LAST CDS_SEC 18
J 0
(-5625 3400);
DISPLAY 1.021277 (-5625 3400);
DISPLAY INVISIBLE (-5625 3400);
FORCEPROP 0 LASTPIN (-5775 3000) $PN CV36
J 2
(-5785 3010);
DISPLAY 0.489362 (-5785 3010);
PAINT MONO (-5785 3010);
FORCEPROP 0 LASTPIN (-5775 2900) $PN CY36
J 2
(-5785 2910);
DISPLAY 0.489362 (-5785 2910);
PAINT MONO (-5785 2910);
FORCEPROP 0 LASTPIN (-5775 2800) $PN DB36
J 2
(-5785 2810);
DISPLAY 0.489362 (-5785 2810);
PAINT MONO (-5785 2810);
FORCEPROP 0 LASTPIN (-5775 2700) $PN CW33
J 2
(-5785 2710);
DISPLAY 0.489362 (-5785 2710);
PAINT MONO (-5785 2710);
FORCEPROP 0 LASTPIN (-5775 2600) $PN DC33
J 2
(-5785 2610);
DISPLAY 0.489362 (-5785 2610);
PAINT MONO (-5785 2610);
FORCEPROP 0 LASTPIN (-5775 2500) $PN DA33
J 2
(-5785 2510);
DISPLAY 0.489362 (-5785 2510);
PAINT MONO (-5785 2510);
FORCEPROP 0 LASTPIN (-5775 2400) $PN CW30
J 2
(-5785 2410);
DISPLAY 0.489362 (-5785 2410);
PAINT MONO (-5785 2410);
FORCEPROP 0 LASTPIN (-5775 2300) $PN DC30
J 2
(-5785 2310);
DISPLAY 0.489362 (-5785 2310);
PAINT MONO (-5785 2310);
FORCEPROP 0 LASTPIN (-5775 2200) $PN DA30
J 2
(-5785 2210);
DISPLAY 0.489362 (-5785 2210);
PAINT MONO (-5785 2210);
FORCEPROP 0 LASTPIN (-5775 2100) $PN CW27
J 2
(-5785 2110);
DISPLAY 0.489362 (-5785 2110);
PAINT MONO (-5785 2110);
FORCEPROP 0 LASTPIN (-5775 2000) $PN DC27
J 2
(-5785 2010);
DISPLAY 0.489362 (-5785 2010);
PAINT MONO (-5785 2010);
FORCEPROP 0 LASTPIN (-5775 1900) $PN DA27
J 2
(-5785 1910);
DISPLAY 0.489362 (-5785 1910);
PAINT MONO (-5785 1910);
FORCEPROP 0 LASTPIN (-5775 1800) $PN CW24
J 2
(-5785 1810);
DISPLAY 0.489362 (-5785 1810);
PAINT MONO (-5785 1810);
FORCEPROP 0 LASTPIN (-5775 1700) $PN DC24
J 2
(-5785 1710);
DISPLAY 0.489362 (-5785 1710);
PAINT MONO (-5785 1710);
FORCEPROP 0 LASTPIN (-5775 1600) $PN DA24
J 2
(-5785 1610);
DISPLAY 0.489362 (-5785 1610);
PAINT MONO (-5785 1610);
FORCEPROP 0 LASTPIN (-5775 1500) $PN CU24
J 2
(-5785 1510);
DISPLAY 0.489362 (-5785 1510);
PAINT MONO (-5785 1510);
FORCEPROP 0 LASTPIN (-5775 3050) $PN CV35
J 2
(-5785 3060);
DISPLAY 0.489362 (-5785 3060);
PAINT MONO (-5785 3060);
FORCEPROP 0 LASTPIN (-5775 2950) $PN CY35
J 2
(-5785 2960);
DISPLAY 0.489362 (-5785 2960);
PAINT MONO (-5785 2960);
FORCEPROP 0 LASTPIN (-5775 2850) $PN DB35
J 2
(-5785 2860);
DISPLAY 0.489362 (-5785 2860);
PAINT MONO (-5785 2860);
FORCEPROP 0 LASTPIN (-5775 2750) $PN CW32
J 2
(-5785 2760);
DISPLAY 0.489362 (-5785 2760);
PAINT MONO (-5785 2760);
FORCEPROP 0 LASTPIN (-5775 2650) $PN DC32
J 2
(-5785 2660);
DISPLAY 0.489362 (-5785 2660);
PAINT MONO (-5785 2660);
FORCEPROP 0 LASTPIN (-5775 2550) $PN DA32
J 2
(-5785 2560);
DISPLAY 0.489362 (-5785 2560);
PAINT MONO (-5785 2560);
FORCEPROP 0 LASTPIN (-5775 2450) $PN CW29
J 2
(-5785 2460);
DISPLAY 0.489362 (-5785 2460);
PAINT MONO (-5785 2460);
FORCEPROP 0 LASTPIN (-5775 2350) $PN DC29
J 2
(-5785 2360);
DISPLAY 0.489362 (-5785 2360);
PAINT MONO (-5785 2360);
FORCEPROP 0 LASTPIN (-5775 2250) $PN DA29
J 2
(-5785 2260);
DISPLAY 0.489362 (-5785 2260);
PAINT MONO (-5785 2260);
FORCEPROP 0 LASTPIN (-5775 2150) $PN CW26
J 2
(-5785 2160);
DISPLAY 0.489362 (-5785 2160);
PAINT MONO (-5785 2160);
FORCEPROP 0 LASTPIN (-5775 2050) $PN DC26
J 2
(-5785 2060);
DISPLAY 0.489362 (-5785 2060);
PAINT MONO (-5785 2060);
FORCEPROP 0 LASTPIN (-5775 1950) $PN DA26
J 2
(-5785 1960);
DISPLAY 0.489362 (-5785 1960);
PAINT MONO (-5785 1960);
FORCEPROP 0 LASTPIN (-5775 1850) $PN CW23
J 2
(-5785 1860);
DISPLAY 0.489362 (-5785 1860);
PAINT MONO (-5785 1860);
FORCEPROP 0 LASTPIN (-5775 1750) $PN DC23
J 2
(-5785 1760);
DISPLAY 0.489362 (-5785 1760);
PAINT MONO (-5785 1760);
FORCEPROP 0 LASTPIN (-5775 1650) $PN DA23
J 2
(-5785 1660);
DISPLAY 0.489362 (-5785 1660);
PAINT MONO (-5785 1660);
FORCEPROP 0 LASTPIN (-5775 1550) $PN CU23
J 2
(-5785 1560);
DISPLAY 0.489362 (-5785 1560);
PAINT MONO (-5785 1560);
FORCEPROP 0 LASTPIN (-4275 3000) $PN CD35
J 0
(-4265 3010);
DISPLAY 0.489362 (-4265 3010);
PAINT MONO (-4265 3010);
FORCEPROP 0 LASTPIN (-4275 2900) $PN CF35
J 0
(-4265 2910);
DISPLAY 0.489362 (-4265 2910);
PAINT MONO (-4265 2910);
FORCEPROP 0 LASTPIN (-4275 2800) $PN CH35
J 0
(-4265 2810);
DISPLAY 0.489362 (-4265 2810);
PAINT MONO (-4265 2810);
FORCEPROP 0 LASTPIN (-4275 2700) $PN CC32
J 0
(-4265 2710);
DISPLAY 0.489362 (-4265 2710);
PAINT MONO (-4265 2710);
FORCEPROP 0 LASTPIN (-4275 2600) $PN CJ32
J 0
(-4265 2610);
DISPLAY 0.489362 (-4265 2610);
PAINT MONO (-4265 2610);
FORCEPROP 0 LASTPIN (-4275 2500) $PN CG32
J 0
(-4265 2510);
DISPLAY 0.489362 (-4265 2510);
PAINT MONO (-4265 2510);
FORCEPROP 0 LASTPIN (-4275 2400) $PN CE32
J 0
(-4265 2410);
DISPLAY 0.489362 (-4265 2410);
PAINT MONO (-4265 2410);
FORCEPROP 0 LASTPIN (-4275 2300) $PN CC29
J 0
(-4265 2310);
DISPLAY 0.489362 (-4265 2310);
PAINT MONO (-4265 2310);
FORCEPROP 0 LASTPIN (-4275 2200) $PN CG29
J 0
(-4265 2210);
DISPLAY 0.489362 (-4265 2210);
PAINT MONO (-4265 2210);
FORCEPROP 0 LASTPIN (-4275 2100) $PN CE29
J 0
(-4265 2110);
DISPLAY 0.489362 (-4265 2110);
PAINT MONO (-4265 2110);
FORCEPROP 0 LASTPIN (-4275 2000) $PN CC26
J 0
(-4265 2010);
DISPLAY 0.489362 (-4265 2010);
PAINT MONO (-4265 2010);
FORCEPROP 0 LASTPIN (-4275 1900) $PN CG26
J 0
(-4265 1910);
DISPLAY 0.489362 (-4265 1910);
PAINT MONO (-4265 1910);
FORCEPROP 0 LASTPIN (-4275 1800) $PN CE26
J 0
(-4265 1810);
DISPLAY 0.489362 (-4265 1810);
PAINT MONO (-4265 1810);
FORCEPROP 0 LASTPIN (-4275 1700) $PN CC23
J 0
(-4265 1710);
DISPLAY 0.489362 (-4265 1710);
PAINT MONO (-4265 1710);
FORCEPROP 0 LASTPIN (-4275 1600) $PN CG23
J 0
(-4265 1610);
DISPLAY 0.489362 (-4265 1610);
PAINT MONO (-4265 1610);
FORCEPROP 0 LASTPIN (-4275 1500) $PN CE23
J 0
(-4265 1510);
DISPLAY 0.489362 (-4265 1510);
PAINT MONO (-4265 1510);
FORCEPROP 0 LASTPIN (-4275 3050) $PN CD36
J 0
(-4265 3060);
DISPLAY 0.489362 (-4265 3060);
PAINT MONO (-4265 3060);
FORCEPROP 0 LASTPIN (-4275 2950) $PN CF36
J 0
(-4265 2960);
DISPLAY 0.489362 (-4265 2960);
PAINT MONO (-4265 2960);
FORCEPROP 0 LASTPIN (-4275 2850) $PN CH36
J 0
(-4265 2860);
DISPLAY 0.489362 (-4265 2860);
PAINT MONO (-4265 2860);
FORCEPROP 0 LASTPIN (-4275 2750) $PN CC33
J 0
(-4265 2760);
DISPLAY 0.489362 (-4265 2760);
PAINT MONO (-4265 2760);
FORCEPROP 0 LASTPIN (-4275 2650) $PN CJ33
J 0
(-4265 2660);
DISPLAY 0.489362 (-4265 2660);
PAINT MONO (-4265 2660);
FORCEPROP 0 LASTPIN (-4275 2550) $PN CG33
J 0
(-4265 2560);
DISPLAY 0.489362 (-4265 2560);
PAINT MONO (-4265 2560);
FORCEPROP 0 LASTPIN (-4275 2450) $PN CE33
J 0
(-4265 2460);
DISPLAY 0.489362 (-4265 2460);
PAINT MONO (-4265 2460);
FORCEPROP 0 LASTPIN (-4275 2350) $PN CC30
J 0
(-4265 2360);
DISPLAY 0.489362 (-4265 2360);
PAINT MONO (-4265 2360);
FORCEPROP 0 LASTPIN (-4275 2250) $PN CG30
J 0
(-4265 2260);
DISPLAY 0.489362 (-4265 2260);
PAINT MONO (-4265 2260);
FORCEPROP 0 LASTPIN (-4275 2150) $PN CE30
J 0
(-4265 2160);
DISPLAY 0.489362 (-4265 2160);
PAINT MONO (-4265 2160);
FORCEPROP 0 LASTPIN (-4275 2050) $PN CC27
J 0
(-4265 2060);
DISPLAY 0.489362 (-4265 2060);
PAINT MONO (-4265 2060);
FORCEPROP 0 LASTPIN (-4275 1950) $PN CG27
J 0
(-4265 1960);
DISPLAY 0.489362 (-4265 1960);
PAINT MONO (-4265 1960);
FORCEPROP 0 LASTPIN (-4275 1850) $PN CE27
J 0
(-4265 1860);
DISPLAY 0.489362 (-4265 1860);
PAINT MONO (-4265 1860);
FORCEPROP 0 LASTPIN (-4275 1750) $PN CC24
J 0
(-4265 1760);
DISPLAY 0.489362 (-4265 1760);
PAINT MONO (-4265 1760);
FORCEPROP 0 LASTPIN (-4275 1650) $PN CG24
J 0
(-4265 1660);
DISPLAY 0.489362 (-4265 1660);
PAINT MONO (-4265 1660);
FORCEPROP 0 LASTPIN (-4275 1550) $PN CE24
J 0
(-4265 1560);
DISPLAY 0.489362 (-4265 1560);
PAINT MONO (-4265 1560);
FORCEPROP 2 LAST PART_TYPE SMLF
J 0
(-5625 3300);
DISPLAY 1.021277 (-5625 3300);
FORCEPROP 1 LAST MATERIAL IO
J 0
(-5620 3232);
DISPLAY 0.489362 (-5620 3232);
PAINT SKYBLUE (-5620 3232);
FORCEPROP 2 LAST VALUE SOCKET6096_13568-001
J 0
(-5625 3250);
DISPLAY 0.489362 (-5625 3250);
PAINT SKYBLUE (-5625 3250);
FORCEPROP 1 LAST CDS_LMAN_SYM_OUTLINE -600,950,600,-950
J 0
(-5025 2250);
DISPLAY 0.468085 (-5025 2250);
PAINT GREEN (-5025 2250);
DISPLAY INVISIBLE (-5025 2250);
FORCEPROP 1 LAST NEEDS_NO_SIZE TRUE
J 0
(-5025 2250);
DISPLAY 0.723404 (-5025 2250);
PAINT GREEN (-5025 2250);
DISPLAY INVISIBLE (-5025 2250);
FORCEPROP 2 LAST CDS_LIB pure_quanta
J 0
(-5025 2250);
DISPLAY INVISIBLE (-5025 2250);
FORCEPROP 1 LAST PATH I148
J 0
(-5025 2250);
DISPLAY 0.723404 (-5025 2250);
PAINT GREEN (-5025 2250);
DISPLAY INVISIBLE (-5025 2250);
FORCEPROP 1 LAST PART_NUMBER DGA^6000030
J 0
(-5620 3359);
DISPLAY 0.489362 (-5620 3359);
PAINT SKYBLUE (-5620 3359);
DISPLAY INVISIBLE (-5620 3359);
FORCEADD OFFPAGE..2
(-2975 6075);
FORCEPROP 2 LAST $XR0 64 
J 0
(-2786 6075);
DISPLAY 0.638298 (-2786 6075);
PAINT MONO (-2786 6075);
FORCEPROP 2 LAST CDS_LIB standard
J 0
(-2975 6075);
DISPLAY INVISIBLE (-2975 6075);
FORCEPROP 1 LAST OFFPAGE TRUE
J 0
(-2650 5950);
DISPLAY 0.872340 (-2650 5950);
PAINT GREEN (-2650 5950);
DISPLAY INVISIBLE (-2650 5950);
FORCEPROP 1 LAST COMMENT_BODY TRUE
J 0
(-3020 5980);
DISPLAY 0.872340 (-3020 5980);
PAINT GREEN (-3020 5980);
DISPLAY INVISIBLE (-3020 5980);
FORCEPROP 2 LAST PATH I149
J 0
(-2775 6125);
DISPLAY 1.021277 (-2775 6125);
DISPLAY INVISIBLE (-2775 6125);
FORCEADD OFFPAGE..2
(-2975 6025);
FORCEPROP 2 LAST $XR0 64 
J 0
(-2786 6025);
DISPLAY 0.638298 (-2786 6025);
PAINT MONO (-2786 6025);
FORCEPROP 2 LAST CDS_LIB standard
J 0
(-2975 6025);
DISPLAY INVISIBLE (-2975 6025);
FORCEPROP 1 LAST OFFPAGE TRUE
J 0
(-2650 5900);
DISPLAY 0.872340 (-2650 5900);
PAINT GREEN (-2650 5900);
DISPLAY INVISIBLE (-2650 5900);
FORCEPROP 1 LAST COMMENT_BODY TRUE
J 0
(-3020 5930);
DISPLAY 0.872340 (-3020 5930);
PAINT GREEN (-3020 5930);
DISPLAY INVISIBLE (-3020 5930);
FORCEPROP 2 LAST PATH I150
J 0
(-2775 6075);
DISPLAY 1.021277 (-2775 6075);
DISPLAY INVISIBLE (-2775 6075);
FORCEADD TAP..6
R 2
(-3700 5725);
FORCEPROP 3 LASTPIN (-3750 5725) SIG_NAME P5E_CPU0_P2_TX_DN<1>
J 0
(-3740 5735);
DISPLAY 0.659574 (-3740 5735);
PAINT MONO (-3740 5735);
DISPLAY INVISIBLE (-3740 5735);
FORCEPROP 1 LASTPIN (-3750 5725) BN 1
J 2
(-3698 5733);
DISPLAY 0.489362 (-3698 5733);
PAINT MONO (-3698 5733);
FORCEPROP 2 LAST BOM_COST IO_SLOT
J 0
(-4200 5825);
DISPLAY 0.829787 (-4200 5825);
DISPLAY INVISIBLE (-4200 5825);
FORCEPROP 2 LAST ROOM RISER1
J 0
(-4200 5775);
DISPLAY 0.829787 (-4200 5775);
PAINT RED (-4200 5775);
DISPLAY INVISIBLE (-4200 5775);
FORCEPROP 2 LAST CDS_LIB mstr_standard
J 0
(-3700 5725);
DISPLAY INVISIBLE (-3700 5725);
FORCEPROP 1 LAST BODY_TYPE PLUMBING
J 2
(-3700 5675);
DISPLAY 0.702128 (-3700 5675);
PAINT GREEN (-3700 5675);
DISPLAY INVISIBLE (-3700 5675);
FORCEPROP 1 LAST HDL_TAP TRUE
J 2
(-4025 5600);
DISPLAY 0.702128 (-4025 5600);
PAINT GREEN (-4025 5600);
DISPLAY INVISIBLE (-4025 5600);
FORCEPROP 1 LAST PATH I151
J 2
(-3698 5725);
DISPLAY 0.872340 (-3698 5725);
PAINT GREEN (-3698 5725);
DISPLAY INVISIBLE (-3698 5725);
FORCEADD TAP..6
R 2
(-3700 5825);
FORCEPROP 3 LASTPIN (-3750 5825) SIG_NAME P5E_CPU0_P2_TX_DN<0>
J 0
(-3740 5835);
DISPLAY 0.659574 (-3740 5835);
PAINT MONO (-3740 5835);
DISPLAY INVISIBLE (-3740 5835);
FORCEPROP 1 LASTPIN (-3750 5825) BN 0
J 2
(-3698 5833);
DISPLAY 0.489362 (-3698 5833);
PAINT MONO (-3698 5833);
FORCEPROP 2 LAST BOM_COST IO_SLOT
J 0
(-4200 5925);
DISPLAY 0.829787 (-4200 5925);
DISPLAY INVISIBLE (-4200 5925);
FORCEPROP 2 LAST ROOM RISER1
J 0
(-4200 5875);
DISPLAY 0.829787 (-4200 5875);
PAINT RED (-4200 5875);
DISPLAY INVISIBLE (-4200 5875);
FORCEPROP 2 LAST CDS_LIB mstr_standard
J 0
(-3700 5825);
DISPLAY INVISIBLE (-3700 5825);
FORCEPROP 1 LAST BODY_TYPE PLUMBING
J 2
(-3700 5775);
DISPLAY 0.702128 (-3700 5775);
PAINT GREEN (-3700 5775);
DISPLAY INVISIBLE (-3700 5775);
FORCEPROP 1 LAST HDL_TAP TRUE
J 2
(-4025 5700);
DISPLAY 0.702128 (-4025 5700);
PAINT GREEN (-4025 5700);
DISPLAY INVISIBLE (-4025 5700);
FORCEPROP 1 LAST PATH I152
J 2
(-3698 5825);
DISPLAY 0.872340 (-3698 5825);
PAINT GREEN (-3698 5825);
DISPLAY INVISIBLE (-3698 5825);
FORCEADD TAP..6
R 2
(-3850 5875);
FORCEPROP 3 LASTPIN (-3900 5875) SIG_NAME P5E_CPU0_P2_TX_DP<0>
J 0
(-3890 5885);
DISPLAY 0.659574 (-3890 5885);
PAINT MONO (-3890 5885);
DISPLAY INVISIBLE (-3890 5885);
FORCEPROP 1 LASTPIN (-3900 5875) BN 0
J 2
(-3848 5883);
DISPLAY 0.489362 (-3848 5883);
PAINT MONO (-3848 5883);
FORCEPROP 2 LAST BOM_COST IO_SLOT
J 0
(-4350 5975);
DISPLAY 0.829787 (-4350 5975);
DISPLAY INVISIBLE (-4350 5975);
FORCEPROP 2 LAST ROOM RISER1
J 0
(-4350 5925);
DISPLAY 0.829787 (-4350 5925);
PAINT RED (-4350 5925);
DISPLAY INVISIBLE (-4350 5925);
FORCEPROP 2 LAST CDS_LIB mstr_standard
J 0
(-3850 5875);
DISPLAY INVISIBLE (-3850 5875);
FORCEPROP 1 LAST BODY_TYPE PLUMBING
J 2
(-3850 5825);
DISPLAY 0.702128 (-3850 5825);
PAINT GREEN (-3850 5825);
DISPLAY INVISIBLE (-3850 5825);
FORCEPROP 1 LAST HDL_TAP TRUE
J 2
(-4175 5750);
DISPLAY 0.702128 (-4175 5750);
PAINT GREEN (-4175 5750);
DISPLAY INVISIBLE (-4175 5750);
FORCEPROP 1 LAST PATH I153
J 2
(-3848 5875);
DISPLAY 0.872340 (-3848 5875);
PAINT GREEN (-3848 5875);
DISPLAY INVISIBLE (-3848 5875);
FORCEADD TAP..6
R 2
(-3850 5775);
FORCEPROP 3 LASTPIN (-3900 5775) SIG_NAME P5E_CPU0_P2_TX_DP<1>
J 0
(-3890 5785);
DISPLAY 0.659574 (-3890 5785);
PAINT MONO (-3890 5785);
DISPLAY INVISIBLE (-3890 5785);
FORCEPROP 1 LASTPIN (-3900 5775) BN 1
J 2
(-3848 5783);
DISPLAY 0.489362 (-3848 5783);
PAINT MONO (-3848 5783);
FORCEPROP 2 LAST BOM_COST IO_SLOT
J 0
(-4350 5875);
DISPLAY 0.829787 (-4350 5875);
DISPLAY INVISIBLE (-4350 5875);
FORCEPROP 2 LAST ROOM RISER1
J 0
(-4350 5825);
DISPLAY 0.829787 (-4350 5825);
PAINT RED (-4350 5825);
DISPLAY INVISIBLE (-4350 5825);
FORCEPROP 2 LAST CDS_LIB mstr_standard
J 0
(-3850 5775);
DISPLAY INVISIBLE (-3850 5775);
FORCEPROP 1 LAST BODY_TYPE PLUMBING
J 2
(-3850 5725);
DISPLAY 0.702128 (-3850 5725);
PAINT GREEN (-3850 5725);
DISPLAY INVISIBLE (-3850 5725);
FORCEPROP 1 LAST HDL_TAP TRUE
J 2
(-4175 5650);
DISPLAY 0.702128 (-4175 5650);
PAINT GREEN (-4175 5650);
DISPLAY INVISIBLE (-4175 5650);
FORCEPROP 1 LAST PATH I154
J 2
(-3848 5775);
DISPLAY 0.872340 (-3848 5775);
PAINT GREEN (-3848 5775);
DISPLAY INVISIBLE (-3848 5775);
FORCEADD TAP..6
R 2
(-3700 5625);
FORCEPROP 3 LASTPIN (-3750 5625) SIG_NAME P5E_CPU0_P2_TX_DN<2>
J 0
(-3740 5635);
DISPLAY 0.659574 (-3740 5635);
PAINT MONO (-3740 5635);
DISPLAY INVISIBLE (-3740 5635);
FORCEPROP 1 LASTPIN (-3750 5625) BN 2
J 2
(-3698 5633);
DISPLAY 0.489362 (-3698 5633);
PAINT MONO (-3698 5633);
FORCEPROP 2 LAST BOM_COST IO_SLOT
J 0
(-4200 5725);
DISPLAY 0.829787 (-4200 5725);
DISPLAY INVISIBLE (-4200 5725);
FORCEPROP 2 LAST ROOM RISER1
J 0
(-4200 5675);
DISPLAY 0.829787 (-4200 5675);
PAINT RED (-4200 5675);
DISPLAY INVISIBLE (-4200 5675);
FORCEPROP 2 LAST CDS_LIB standard
J 0
(-3700 5625);
DISPLAY INVISIBLE (-3700 5625);
FORCEPROP 1 LAST BODY_TYPE PLUMBING
J 2
(-3700 5575);
DISPLAY 0.702128 (-3700 5575);
PAINT GREEN (-3700 5575);
DISPLAY INVISIBLE (-3700 5575);
FORCEPROP 1 LAST HDL_TAP TRUE
J 2
(-4025 5500);
DISPLAY 0.702128 (-4025 5500);
PAINT GREEN (-4025 5500);
DISPLAY INVISIBLE (-4025 5500);
FORCEPROP 1 LAST PATH I155
J 2
(-3698 5625);
DISPLAY 0.872340 (-3698 5625);
PAINT GREEN (-3698 5625);
DISPLAY INVISIBLE (-3698 5625);
FORCEADD TAP..6
R 2
(-3700 5525);
FORCEPROP 3 LASTPIN (-3750 5525) SIG_NAME P5E_CPU0_P2_TX_DN<3>
J 0
(-3740 5535);
DISPLAY 0.659574 (-3740 5535);
PAINT MONO (-3740 5535);
DISPLAY INVISIBLE (-3740 5535);
FORCEPROP 1 LASTPIN (-3750 5525) BN 3
J 2
(-3698 5533);
DISPLAY 0.489362 (-3698 5533);
PAINT MONO (-3698 5533);
FORCEPROP 2 LAST BOM_COST IO_SLOT
J 0
(-4200 5625);
DISPLAY 0.829787 (-4200 5625);
DISPLAY INVISIBLE (-4200 5625);
FORCEPROP 2 LAST ROOM RISER1
J 0
(-4200 5575);
DISPLAY 0.829787 (-4200 5575);
PAINT RED (-4200 5575);
DISPLAY INVISIBLE (-4200 5575);
FORCEPROP 2 LAST CDS_LIB standard
J 0
(-3700 5525);
DISPLAY INVISIBLE (-3700 5525);
FORCEPROP 1 LAST BODY_TYPE PLUMBING
J 2
(-3700 5475);
DISPLAY 0.702128 (-3700 5475);
PAINT GREEN (-3700 5475);
DISPLAY INVISIBLE (-3700 5475);
FORCEPROP 1 LAST HDL_TAP TRUE
J 2
(-4025 5400);
DISPLAY 0.702128 (-4025 5400);
PAINT GREEN (-4025 5400);
DISPLAY INVISIBLE (-4025 5400);
FORCEPROP 1 LAST PATH I156
J 2
(-3698 5525);
DISPLAY 0.872340 (-3698 5525);
PAINT GREEN (-3698 5525);
DISPLAY INVISIBLE (-3698 5525);
FORCEADD TAP..6
R 2
(-3850 5675);
FORCEPROP 3 LASTPIN (-3900 5675) SIG_NAME P5E_CPU0_P2_TX_DP<2>
J 0
(-3890 5685);
DISPLAY 0.659574 (-3890 5685);
PAINT MONO (-3890 5685);
DISPLAY INVISIBLE (-3890 5685);
FORCEPROP 1 LASTPIN (-3900 5675) BN 2
J 2
(-3848 5683);
DISPLAY 0.489362 (-3848 5683);
PAINT MONO (-3848 5683);
FORCEPROP 2 LAST BOM_COST IO_SLOT
J 0
(-4350 5775);
DISPLAY 0.829787 (-4350 5775);
DISPLAY INVISIBLE (-4350 5775);
FORCEPROP 2 LAST ROOM RISER1
J 0
(-4350 5725);
DISPLAY 0.829787 (-4350 5725);
PAINT RED (-4350 5725);
DISPLAY INVISIBLE (-4350 5725);
FORCEPROP 2 LAST CDS_LIB standard
J 0
(-3850 5675);
DISPLAY INVISIBLE (-3850 5675);
FORCEPROP 1 LAST BODY_TYPE PLUMBING
J 2
(-3850 5625);
DISPLAY 0.702128 (-3850 5625);
PAINT GREEN (-3850 5625);
DISPLAY INVISIBLE (-3850 5625);
FORCEPROP 1 LAST HDL_TAP TRUE
J 2
(-4175 5550);
DISPLAY 0.702128 (-4175 5550);
PAINT GREEN (-4175 5550);
DISPLAY INVISIBLE (-4175 5550);
FORCEPROP 1 LAST PATH I157
J 2
(-3848 5675);
DISPLAY 0.872340 (-3848 5675);
PAINT GREEN (-3848 5675);
DISPLAY INVISIBLE (-3848 5675);
FORCEADD TAP..6
R 2
(-3850 5575);
FORCEPROP 3 LASTPIN (-3900 5575) SIG_NAME P5E_CPU0_P2_TX_DP<3>
J 0
(-3890 5585);
DISPLAY 0.659574 (-3890 5585);
PAINT MONO (-3890 5585);
DISPLAY INVISIBLE (-3890 5585);
FORCEPROP 1 LASTPIN (-3900 5575) BN 3
J 2
(-3848 5583);
DISPLAY 0.489362 (-3848 5583);
PAINT MONO (-3848 5583);
FORCEPROP 2 LAST BOM_COST IO_SLOT
J 0
(-4350 5675);
DISPLAY 0.829787 (-4350 5675);
DISPLAY INVISIBLE (-4350 5675);
FORCEPROP 2 LAST ROOM RISER1
J 0
(-4350 5625);
DISPLAY 0.829787 (-4350 5625);
PAINT RED (-4350 5625);
DISPLAY INVISIBLE (-4350 5625);
FORCEPROP 2 LAST CDS_LIB standard
J 0
(-3850 5575);
DISPLAY INVISIBLE (-3850 5575);
FORCEPROP 1 LAST BODY_TYPE PLUMBING
J 2
(-3850 5525);
DISPLAY 0.702128 (-3850 5525);
PAINT GREEN (-3850 5525);
DISPLAY INVISIBLE (-3850 5525);
FORCEPROP 1 LAST HDL_TAP TRUE
J 2
(-4175 5450);
DISPLAY 0.702128 (-4175 5450);
PAINT GREEN (-4175 5450);
DISPLAY INVISIBLE (-4175 5450);
FORCEPROP 1 LAST PATH I158
J 2
(-3848 5575);
DISPLAY 0.872340 (-3848 5575);
PAINT GREEN (-3848 5575);
DISPLAY INVISIBLE (-3848 5575);
FORCEADD TAP..6
R 2
(-3850 5475);
FORCEPROP 3 LASTPIN (-3900 5475) SIG_NAME P5E_CPU0_P2_TX_DP<4>
J 0
(-3890 5485);
DISPLAY 0.659574 (-3890 5485);
PAINT MONO (-3890 5485);
DISPLAY INVISIBLE (-3890 5485);
FORCEPROP 1 LASTPIN (-3900 5475) BN 4
J 2
(-3848 5483);
DISPLAY 0.489362 (-3848 5483);
PAINT MONO (-3848 5483);
FORCEPROP 2 LAST BOM_COST IO_SLOT
J 0
(-4350 5575);
DISPLAY 0.829787 (-4350 5575);
DISPLAY INVISIBLE (-4350 5575);
FORCEPROP 2 LAST ROOM RISER1
J 0
(-4350 5525);
DISPLAY 0.829787 (-4350 5525);
PAINT RED (-4350 5525);
DISPLAY INVISIBLE (-4350 5525);
FORCEPROP 2 LAST CDS_LIB standard
J 0
(-3850 5475);
DISPLAY INVISIBLE (-3850 5475);
FORCEPROP 1 LAST BODY_TYPE PLUMBING
J 2
(-3850 5425);
DISPLAY 0.702128 (-3850 5425);
PAINT GREEN (-3850 5425);
DISPLAY INVISIBLE (-3850 5425);
FORCEPROP 1 LAST HDL_TAP TRUE
J 2
(-4175 5350);
DISPLAY 0.702128 (-4175 5350);
PAINT GREEN (-4175 5350);
DISPLAY INVISIBLE (-4175 5350);
FORCEPROP 1 LAST PATH I159
J 2
(-3848 5475);
DISPLAY 0.872340 (-3848 5475);
PAINT GREEN (-3848 5475);
DISPLAY INVISIBLE (-3848 5475);
FORCEADD TAP..6
R 2
(-3700 5325);
FORCEPROP 3 LASTPIN (-3750 5325) SIG_NAME P5E_CPU0_P2_TX_DN<5>
J 0
(-3740 5335);
DISPLAY 0.659574 (-3740 5335);
PAINT MONO (-3740 5335);
DISPLAY INVISIBLE (-3740 5335);
FORCEPROP 1 LASTPIN (-3750 5325) BN 5
J 2
(-3698 5333);
DISPLAY 0.489362 (-3698 5333);
PAINT MONO (-3698 5333);
FORCEPROP 2 LAST BOM_COST IO_SLOT
J 0
(-4200 5425);
DISPLAY 0.829787 (-4200 5425);
DISPLAY INVISIBLE (-4200 5425);
FORCEPROP 2 LAST ROOM RISER1
J 0
(-4200 5375);
DISPLAY 0.829787 (-4200 5375);
PAINT RED (-4200 5375);
DISPLAY INVISIBLE (-4200 5375);
FORCEPROP 2 LAST CDS_LIB standard
J 0
(-3700 5325);
DISPLAY INVISIBLE (-3700 5325);
FORCEPROP 1 LAST BODY_TYPE PLUMBING
J 2
(-3700 5275);
DISPLAY 0.702128 (-3700 5275);
PAINT GREEN (-3700 5275);
DISPLAY INVISIBLE (-3700 5275);
FORCEPROP 1 LAST HDL_TAP TRUE
J 2
(-4025 5200);
DISPLAY 0.702128 (-4025 5200);
PAINT GREEN (-4025 5200);
DISPLAY INVISIBLE (-4025 5200);
FORCEPROP 1 LAST PATH I160
J 2
(-3698 5325);
DISPLAY 0.872340 (-3698 5325);
PAINT GREEN (-3698 5325);
DISPLAY INVISIBLE (-3698 5325);
FORCEADD TAP..6
R 2
(-3700 5425);
FORCEPROP 3 LASTPIN (-3750 5425) SIG_NAME P5E_CPU0_P2_TX_DN<4>
J 0
(-3740 5435);
DISPLAY 0.659574 (-3740 5435);
PAINT MONO (-3740 5435);
DISPLAY INVISIBLE (-3740 5435);
FORCEPROP 1 LASTPIN (-3750 5425) BN 4
J 2
(-3698 5433);
DISPLAY 0.489362 (-3698 5433);
PAINT MONO (-3698 5433);
FORCEPROP 2 LAST BOM_COST IO_SLOT
J 0
(-4200 5525);
DISPLAY 0.829787 (-4200 5525);
DISPLAY INVISIBLE (-4200 5525);
FORCEPROP 2 LAST ROOM RISER1
J 0
(-4200 5475);
DISPLAY 0.829787 (-4200 5475);
PAINT RED (-4200 5475);
DISPLAY INVISIBLE (-4200 5475);
FORCEPROP 2 LAST CDS_LIB standard
J 0
(-3700 5425);
DISPLAY INVISIBLE (-3700 5425);
FORCEPROP 1 LAST BODY_TYPE PLUMBING
J 2
(-3700 5375);
DISPLAY 0.702128 (-3700 5375);
PAINT GREEN (-3700 5375);
DISPLAY INVISIBLE (-3700 5375);
FORCEPROP 1 LAST HDL_TAP TRUE
J 2
(-4025 5300);
DISPLAY 0.702128 (-4025 5300);
PAINT GREEN (-4025 5300);
DISPLAY INVISIBLE (-4025 5300);
FORCEPROP 1 LAST PATH I161
J 2
(-3698 5425);
DISPLAY 0.872340 (-3698 5425);
PAINT GREEN (-3698 5425);
DISPLAY INVISIBLE (-3698 5425);
FORCEADD TAP..6
R 2
(-3700 5225);
FORCEPROP 3 LASTPIN (-3750 5225) SIG_NAME P5E_CPU0_P2_TX_DN<6>
J 0
(-3740 5235);
DISPLAY 0.659574 (-3740 5235);
PAINT MONO (-3740 5235);
DISPLAY INVISIBLE (-3740 5235);
FORCEPROP 1 LASTPIN (-3750 5225) BN 6
J 2
(-3698 5233);
DISPLAY 0.489362 (-3698 5233);
PAINT MONO (-3698 5233);
FORCEPROP 2 LAST BOM_COST IO_SLOT
J 0
(-4200 5325);
DISPLAY 0.829787 (-4200 5325);
DISPLAY INVISIBLE (-4200 5325);
FORCEPROP 2 LAST ROOM RISER1
J 0
(-4200 5275);
DISPLAY 0.829787 (-4200 5275);
PAINT RED (-4200 5275);
DISPLAY INVISIBLE (-4200 5275);
FORCEPROP 2 LAST CDS_LIB standard
J 0
(-3700 5225);
DISPLAY INVISIBLE (-3700 5225);
FORCEPROP 1 LAST BODY_TYPE PLUMBING
J 2
(-3700 5175);
DISPLAY 0.702128 (-3700 5175);
PAINT GREEN (-3700 5175);
DISPLAY INVISIBLE (-3700 5175);
FORCEPROP 1 LAST HDL_TAP TRUE
J 2
(-4025 5100);
DISPLAY 0.702128 (-4025 5100);
PAINT GREEN (-4025 5100);
DISPLAY INVISIBLE (-4025 5100);
FORCEPROP 1 LAST PATH I162
J 2
(-3698 5225);
DISPLAY 0.872340 (-3698 5225);
PAINT GREEN (-3698 5225);
DISPLAY INVISIBLE (-3698 5225);
FORCEADD TAP..6
R 2
(-3850 5375);
FORCEPROP 3 LASTPIN (-3900 5375) SIG_NAME P5E_CPU0_P2_TX_DP<5>
J 0
(-3890 5385);
DISPLAY 0.659574 (-3890 5385);
PAINT MONO (-3890 5385);
DISPLAY INVISIBLE (-3890 5385);
FORCEPROP 1 LASTPIN (-3900 5375) BN 5
J 2
(-3848 5383);
DISPLAY 0.489362 (-3848 5383);
PAINT MONO (-3848 5383);
FORCEPROP 2 LAST BOM_COST IO_SLOT
J 0
(-4350 5475);
DISPLAY 0.829787 (-4350 5475);
DISPLAY INVISIBLE (-4350 5475);
FORCEPROP 2 LAST ROOM RISER1
J 0
(-4350 5425);
DISPLAY 0.829787 (-4350 5425);
PAINT RED (-4350 5425);
DISPLAY INVISIBLE (-4350 5425);
FORCEPROP 2 LAST CDS_LIB standard
J 0
(-3850 5375);
DISPLAY INVISIBLE (-3850 5375);
FORCEPROP 1 LAST BODY_TYPE PLUMBING
J 2
(-3850 5325);
DISPLAY 0.702128 (-3850 5325);
PAINT GREEN (-3850 5325);
DISPLAY INVISIBLE (-3850 5325);
FORCEPROP 1 LAST HDL_TAP TRUE
J 2
(-4175 5250);
DISPLAY 0.702128 (-4175 5250);
PAINT GREEN (-4175 5250);
DISPLAY INVISIBLE (-4175 5250);
FORCEPROP 1 LAST PATH I163
J 2
(-3848 5375);
DISPLAY 0.872340 (-3848 5375);
PAINT GREEN (-3848 5375);
DISPLAY INVISIBLE (-3848 5375);
FORCEADD TAP..6
R 2
(-3850 5275);
FORCEPROP 3 LASTPIN (-3900 5275) SIG_NAME P5E_CPU0_P2_TX_DP<6>
J 0
(-3890 5285);
DISPLAY 0.659574 (-3890 5285);
PAINT MONO (-3890 5285);
DISPLAY INVISIBLE (-3890 5285);
FORCEPROP 1 LASTPIN (-3900 5275) BN 6
J 2
(-3848 5283);
DISPLAY 0.489362 (-3848 5283);
PAINT MONO (-3848 5283);
FORCEPROP 2 LAST BOM_COST IO_SLOT
J 0
(-4350 5375);
DISPLAY 0.829787 (-4350 5375);
DISPLAY INVISIBLE (-4350 5375);
FORCEPROP 2 LAST ROOM RISER1
J 0
(-4350 5325);
DISPLAY 0.829787 (-4350 5325);
PAINT RED (-4350 5325);
DISPLAY INVISIBLE (-4350 5325);
FORCEPROP 2 LAST CDS_LIB standard
J 0
(-3850 5275);
DISPLAY INVISIBLE (-3850 5275);
FORCEPROP 1 LAST BODY_TYPE PLUMBING
J 2
(-3850 5225);
DISPLAY 0.702128 (-3850 5225);
PAINT GREEN (-3850 5225);
DISPLAY INVISIBLE (-3850 5225);
FORCEPROP 1 LAST HDL_TAP TRUE
J 2
(-4175 5150);
DISPLAY 0.702128 (-4175 5150);
PAINT GREEN (-4175 5150);
DISPLAY INVISIBLE (-4175 5150);
FORCEPROP 1 LAST PATH I164
J 2
(-3848 5275);
DISPLAY 0.872340 (-3848 5275);
PAINT GREEN (-3848 5275);
DISPLAY INVISIBLE (-3848 5275);
FORCEADD TAP..6
R 2
(-3700 5125);
FORCEPROP 3 LASTPIN (-3750 5125) SIG_NAME P5E_CPU0_P2_TX_DN<7>
J 0
(-3740 5135);
DISPLAY 0.659574 (-3740 5135);
PAINT MONO (-3740 5135);
DISPLAY INVISIBLE (-3740 5135);
FORCEPROP 1 LASTPIN (-3750 5125) BN 7
J 2
(-3698 5133);
DISPLAY 0.489362 (-3698 5133);
PAINT MONO (-3698 5133);
FORCEPROP 2 LAST BOM_COST IO_SLOT
J 0
(-4200 5225);
DISPLAY 0.829787 (-4200 5225);
DISPLAY INVISIBLE (-4200 5225);
FORCEPROP 2 LAST ROOM RISER1
J 0
(-4200 5175);
DISPLAY 0.829787 (-4200 5175);
PAINT RED (-4200 5175);
DISPLAY INVISIBLE (-4200 5175);
FORCEPROP 2 LAST CDS_LIB standard
J 0
(-3700 5125);
DISPLAY INVISIBLE (-3700 5125);
FORCEPROP 1 LAST BODY_TYPE PLUMBING
J 2
(-3700 5075);
DISPLAY 0.702128 (-3700 5075);
PAINT GREEN (-3700 5075);
DISPLAY INVISIBLE (-3700 5075);
FORCEPROP 1 LAST HDL_TAP TRUE
J 2
(-4025 5000);
DISPLAY 0.702128 (-4025 5000);
PAINT GREEN (-4025 5000);
DISPLAY INVISIBLE (-4025 5000);
FORCEPROP 1 LAST PATH I165
J 2
(-3698 5125);
DISPLAY 0.872340 (-3698 5125);
PAINT GREEN (-3698 5125);
DISPLAY INVISIBLE (-3698 5125);
FORCEADD TAP..6
R 2
(-3700 5025);
FORCEPROP 3 LASTPIN (-3750 5025) SIG_NAME P5E_CPU0_P2_TX_DN<8>
J 0
(-3740 5035);
DISPLAY 0.659574 (-3740 5035);
PAINT MONO (-3740 5035);
DISPLAY INVISIBLE (-3740 5035);
FORCEPROP 1 LASTPIN (-3750 5025) BN 8
J 2
(-3698 5033);
DISPLAY 0.489362 (-3698 5033);
PAINT MONO (-3698 5033);
FORCEPROP 2 LAST BOM_COST IO_SLOT
J 0
(-4200 5125);
DISPLAY 0.829787 (-4200 5125);
DISPLAY INVISIBLE (-4200 5125);
FORCEPROP 2 LAST ROOM RISER1
J 0
(-4200 5075);
DISPLAY 0.829787 (-4200 5075);
PAINT RED (-4200 5075);
DISPLAY INVISIBLE (-4200 5075);
FORCEPROP 2 LAST CDS_LIB standard
J 0
(-3700 5025);
DISPLAY INVISIBLE (-3700 5025);
FORCEPROP 1 LAST BODY_TYPE PLUMBING
J 2
(-3700 4975);
DISPLAY 0.702128 (-3700 4975);
PAINT GREEN (-3700 4975);
DISPLAY INVISIBLE (-3700 4975);
FORCEPROP 1 LAST HDL_TAP TRUE
J 2
(-4025 4900);
DISPLAY 0.702128 (-4025 4900);
PAINT GREEN (-4025 4900);
DISPLAY INVISIBLE (-4025 4900);
FORCEPROP 1 LAST PATH I166
J 2
(-3698 5025);
DISPLAY 0.872340 (-3698 5025);
PAINT GREEN (-3698 5025);
DISPLAY INVISIBLE (-3698 5025);
FORCEADD TAP..6
R 2
(-3850 5175);
FORCEPROP 3 LASTPIN (-3900 5175) SIG_NAME P5E_CPU0_P2_TX_DP<7>
J 0
(-3890 5185);
DISPLAY 0.659574 (-3890 5185);
PAINT MONO (-3890 5185);
DISPLAY INVISIBLE (-3890 5185);
FORCEPROP 1 LASTPIN (-3900 5175) BN 7
J 2
(-3848 5183);
DISPLAY 0.489362 (-3848 5183);
PAINT MONO (-3848 5183);
FORCEPROP 2 LAST BOM_COST IO_SLOT
J 0
(-4350 5275);
DISPLAY 0.829787 (-4350 5275);
DISPLAY INVISIBLE (-4350 5275);
FORCEPROP 2 LAST ROOM RISER1
J 0
(-4350 5225);
DISPLAY 0.829787 (-4350 5225);
PAINT RED (-4350 5225);
DISPLAY INVISIBLE (-4350 5225);
FORCEPROP 2 LAST CDS_LIB standard
J 0
(-3850 5175);
DISPLAY INVISIBLE (-3850 5175);
FORCEPROP 1 LAST BODY_TYPE PLUMBING
J 2
(-3850 5125);
DISPLAY 0.702128 (-3850 5125);
PAINT GREEN (-3850 5125);
DISPLAY INVISIBLE (-3850 5125);
FORCEPROP 1 LAST HDL_TAP TRUE
J 2
(-4175 5050);
DISPLAY 0.702128 (-4175 5050);
PAINT GREEN (-4175 5050);
DISPLAY INVISIBLE (-4175 5050);
FORCEPROP 1 LAST PATH I167
J 2
(-3848 5175);
DISPLAY 0.872340 (-3848 5175);
PAINT GREEN (-3848 5175);
DISPLAY INVISIBLE (-3848 5175);
FORCEADD TAP..6
R 2
(-3850 5075);
FORCEPROP 3 LASTPIN (-3900 5075) SIG_NAME P5E_CPU0_P2_TX_DP<8>
J 0
(-3890 5085);
DISPLAY 0.659574 (-3890 5085);
PAINT MONO (-3890 5085);
DISPLAY INVISIBLE (-3890 5085);
FORCEPROP 1 LASTPIN (-3900 5075) BN 8
J 2
(-3848 5083);
DISPLAY 0.489362 (-3848 5083);
PAINT MONO (-3848 5083);
FORCEPROP 2 LAST BOM_COST IO_SLOT
J 0
(-4350 5175);
DISPLAY 0.829787 (-4350 5175);
DISPLAY INVISIBLE (-4350 5175);
FORCEPROP 2 LAST ROOM RISER1
J 0
(-4350 5125);
DISPLAY 0.829787 (-4350 5125);
PAINT RED (-4350 5125);
DISPLAY INVISIBLE (-4350 5125);
FORCEPROP 2 LAST CDS_LIB standard
J 0
(-3850 5075);
DISPLAY INVISIBLE (-3850 5075);
FORCEPROP 1 LAST BODY_TYPE PLUMBING
J 2
(-3850 5025);
DISPLAY 0.702128 (-3850 5025);
PAINT GREEN (-3850 5025);
DISPLAY INVISIBLE (-3850 5025);
FORCEPROP 1 LAST HDL_TAP TRUE
J 2
(-4175 4950);
DISPLAY 0.702128 (-4175 4950);
PAINT GREEN (-4175 4950);
DISPLAY INVISIBLE (-4175 4950);
FORCEPROP 1 LAST PATH I168
J 2
(-3848 5075);
DISPLAY 0.872340 (-3848 5075);
PAINT GREEN (-3848 5075);
DISPLAY INVISIBLE (-3848 5075);
FORCEADD TAP..6
R 2
(-3850 4975);
FORCEPROP 3 LASTPIN (-3900 4975) SIG_NAME P5E_CPU0_P2_TX_DP<9>
J 0
(-3890 4985);
DISPLAY 0.659574 (-3890 4985);
PAINT MONO (-3890 4985);
DISPLAY INVISIBLE (-3890 4985);
FORCEPROP 1 LASTPIN (-3900 4975) BN 9
J 2
(-3848 4983);
DISPLAY 0.489362 (-3848 4983);
PAINT MONO (-3848 4983);
FORCEPROP 2 LAST BOM_COST IO_SLOT
J 0
(-4350 5075);
DISPLAY 0.829787 (-4350 5075);
DISPLAY INVISIBLE (-4350 5075);
FORCEPROP 2 LAST ROOM RISER1
J 0
(-4350 5025);
DISPLAY 0.829787 (-4350 5025);
PAINT RED (-4350 5025);
DISPLAY INVISIBLE (-4350 5025);
FORCEPROP 2 LAST CDS_LIB standard
J 0
(-3850 4975);
DISPLAY INVISIBLE (-3850 4975);
FORCEPROP 1 LAST BODY_TYPE PLUMBING
J 2
(-3850 4925);
DISPLAY 0.702128 (-3850 4925);
PAINT GREEN (-3850 4925);
DISPLAY INVISIBLE (-3850 4925);
FORCEPROP 1 LAST HDL_TAP TRUE
J 2
(-4175 4850);
DISPLAY 0.702128 (-4175 4850);
PAINT GREEN (-4175 4850);
DISPLAY INVISIBLE (-4175 4850);
FORCEPROP 1 LAST PATH I169
J 2
(-3848 4975);
DISPLAY 0.872340 (-3848 4975);
PAINT GREEN (-3848 4975);
DISPLAY INVISIBLE (-3848 4975);
FORCEADD TAP..6
R 2
(-3700 4825);
FORCEPROP 3 LASTPIN (-3750 4825) SIG_NAME P5E_CPU0_P2_TX_DN<10>
J 0
(-3740 4835);
DISPLAY 0.659574 (-3740 4835);
PAINT MONO (-3740 4835);
DISPLAY INVISIBLE (-3740 4835);
FORCEPROP 1 LASTPIN (-3750 4825) BN 10
J 2
(-3698 4833);
DISPLAY 0.489362 (-3698 4833);
PAINT MONO (-3698 4833);
FORCEPROP 2 LAST BOM_COST IO_SLOT
J 0
(-4200 4925);
DISPLAY 0.829787 (-4200 4925);
DISPLAY INVISIBLE (-4200 4925);
FORCEPROP 2 LAST ROOM RISER1
J 0
(-4200 4875);
DISPLAY 0.829787 (-4200 4875);
PAINT RED (-4200 4875);
DISPLAY INVISIBLE (-4200 4875);
FORCEPROP 2 LAST CDS_LIB standard
J 0
(-3700 4825);
DISPLAY INVISIBLE (-3700 4825);
FORCEPROP 1 LAST BODY_TYPE PLUMBING
J 2
(-3700 4775);
DISPLAY 0.702128 (-3700 4775);
PAINT GREEN (-3700 4775);
DISPLAY INVISIBLE (-3700 4775);
FORCEPROP 1 LAST HDL_TAP TRUE
J 2
(-4025 4700);
DISPLAY 0.702128 (-4025 4700);
PAINT GREEN (-4025 4700);
DISPLAY INVISIBLE (-4025 4700);
FORCEPROP 1 LAST PATH I170
J 2
(-3698 4825);
DISPLAY 0.872340 (-3698 4825);
PAINT GREEN (-3698 4825);
DISPLAY INVISIBLE (-3698 4825);
FORCEADD TAP..6
R 2
(-3700 4925);
FORCEPROP 3 LASTPIN (-3750 4925) SIG_NAME P5E_CPU0_P2_TX_DN<9>
J 0
(-3740 4935);
DISPLAY 0.659574 (-3740 4935);
PAINT MONO (-3740 4935);
DISPLAY INVISIBLE (-3740 4935);
FORCEPROP 1 LASTPIN (-3750 4925) BN 9
J 2
(-3698 4933);
DISPLAY 0.489362 (-3698 4933);
PAINT MONO (-3698 4933);
FORCEPROP 2 LAST BOM_COST IO_SLOT
J 0
(-4200 5025);
DISPLAY 0.829787 (-4200 5025);
DISPLAY INVISIBLE (-4200 5025);
FORCEPROP 2 LAST ROOM RISER1
J 0
(-4200 4975);
DISPLAY 0.829787 (-4200 4975);
PAINT RED (-4200 4975);
DISPLAY INVISIBLE (-4200 4975);
FORCEPROP 2 LAST CDS_LIB standard
J 0
(-3700 4925);
DISPLAY INVISIBLE (-3700 4925);
FORCEPROP 1 LAST BODY_TYPE PLUMBING
J 2
(-3700 4875);
DISPLAY 0.702128 (-3700 4875);
PAINT GREEN (-3700 4875);
DISPLAY INVISIBLE (-3700 4875);
FORCEPROP 1 LAST HDL_TAP TRUE
J 2
(-4025 4800);
DISPLAY 0.702128 (-4025 4800);
PAINT GREEN (-4025 4800);
DISPLAY INVISIBLE (-4025 4800);
FORCEPROP 1 LAST PATH I171
J 2
(-3698 4925);
DISPLAY 0.872340 (-3698 4925);
PAINT GREEN (-3698 4925);
DISPLAY INVISIBLE (-3698 4925);
FORCEADD TAP..6
R 2
(-3700 4725);
FORCEPROP 3 LASTPIN (-3750 4725) SIG_NAME P5E_CPU0_P2_TX_DN<11>
J 0
(-3740 4735);
DISPLAY 0.659574 (-3740 4735);
PAINT MONO (-3740 4735);
DISPLAY INVISIBLE (-3740 4735);
FORCEPROP 1 LASTPIN (-3750 4725) BN 11
J 2
(-3698 4733);
DISPLAY 0.489362 (-3698 4733);
PAINT MONO (-3698 4733);
FORCEPROP 2 LAST BOM_COST IO_SLOT
J 0
(-4200 4825);
DISPLAY 0.829787 (-4200 4825);
DISPLAY INVISIBLE (-4200 4825);
FORCEPROP 2 LAST ROOM RISER1
J 0
(-4200 4775);
DISPLAY 0.829787 (-4200 4775);
PAINT RED (-4200 4775);
DISPLAY INVISIBLE (-4200 4775);
FORCEPROP 2 LAST CDS_LIB standard
J 0
(-3700 4725);
DISPLAY INVISIBLE (-3700 4725);
FORCEPROP 1 LAST BODY_TYPE PLUMBING
J 2
(-3700 4675);
DISPLAY 0.702128 (-3700 4675);
PAINT GREEN (-3700 4675);
DISPLAY INVISIBLE (-3700 4675);
FORCEPROP 1 LAST HDL_TAP TRUE
J 2
(-4025 4600);
DISPLAY 0.702128 (-4025 4600);
PAINT GREEN (-4025 4600);
DISPLAY INVISIBLE (-4025 4600);
FORCEPROP 1 LAST PATH I172
J 2
(-3698 4725);
DISPLAY 0.872340 (-3698 4725);
PAINT GREEN (-3698 4725);
DISPLAY INVISIBLE (-3698 4725);
FORCEADD TAP..6
R 2
(-3850 4875);
FORCEPROP 3 LASTPIN (-3900 4875) SIG_NAME P5E_CPU0_P2_TX_DP<10>
J 0
(-3890 4885);
DISPLAY 0.659574 (-3890 4885);
PAINT MONO (-3890 4885);
DISPLAY INVISIBLE (-3890 4885);
FORCEPROP 1 LASTPIN (-3900 4875) BN 10
J 2
(-3848 4883);
DISPLAY 0.489362 (-3848 4883);
PAINT MONO (-3848 4883);
FORCEPROP 2 LAST BOM_COST IO_SLOT
J 0
(-4350 4975);
DISPLAY 0.829787 (-4350 4975);
DISPLAY INVISIBLE (-4350 4975);
FORCEPROP 2 LAST ROOM RISER1
J 0
(-4350 4925);
DISPLAY 0.829787 (-4350 4925);
PAINT RED (-4350 4925);
DISPLAY INVISIBLE (-4350 4925);
FORCEPROP 2 LAST CDS_LIB standard
J 0
(-3850 4875);
DISPLAY INVISIBLE (-3850 4875);
FORCEPROP 1 LAST BODY_TYPE PLUMBING
J 2
(-3850 4825);
DISPLAY 0.702128 (-3850 4825);
PAINT GREEN (-3850 4825);
DISPLAY INVISIBLE (-3850 4825);
FORCEPROP 1 LAST HDL_TAP TRUE
J 2
(-4175 4750);
DISPLAY 0.702128 (-4175 4750);
PAINT GREEN (-4175 4750);
DISPLAY INVISIBLE (-4175 4750);
FORCEPROP 1 LAST PATH I173
J 2
(-3848 4875);
DISPLAY 0.872340 (-3848 4875);
PAINT GREEN (-3848 4875);
DISPLAY INVISIBLE (-3848 4875);
FORCEADD TAP..6
R 2
(-3850 4775);
FORCEPROP 3 LASTPIN (-3900 4775) SIG_NAME P5E_CPU0_P2_TX_DP<11>
J 0
(-3890 4785);
DISPLAY 0.659574 (-3890 4785);
PAINT MONO (-3890 4785);
DISPLAY INVISIBLE (-3890 4785);
FORCEPROP 1 LASTPIN (-3900 4775) BN 11
J 2
(-3848 4783);
DISPLAY 0.489362 (-3848 4783);
PAINT MONO (-3848 4783);
FORCEPROP 2 LAST BOM_COST IO_SLOT
J 0
(-4350 4875);
DISPLAY 0.829787 (-4350 4875);
DISPLAY INVISIBLE (-4350 4875);
FORCEPROP 2 LAST ROOM RISER1
J 0
(-4350 4825);
DISPLAY 0.829787 (-4350 4825);
PAINT RED (-4350 4825);
DISPLAY INVISIBLE (-4350 4825);
FORCEPROP 2 LAST CDS_LIB standard
J 0
(-3850 4775);
DISPLAY INVISIBLE (-3850 4775);
FORCEPROP 1 LAST BODY_TYPE PLUMBING
J 2
(-3850 4725);
DISPLAY 0.702128 (-3850 4725);
PAINT GREEN (-3850 4725);
DISPLAY INVISIBLE (-3850 4725);
FORCEPROP 1 LAST HDL_TAP TRUE
J 2
(-4175 4650);
DISPLAY 0.702128 (-4175 4650);
PAINT GREEN (-4175 4650);
DISPLAY INVISIBLE (-4175 4650);
FORCEPROP 1 LAST PATH I174
J 2
(-3848 4775);
DISPLAY 0.872340 (-3848 4775);
PAINT GREEN (-3848 4775);
DISPLAY INVISIBLE (-3848 4775);
FORCEADD TAP..6
R 2
(-3700 4625);
FORCEPROP 3 LASTPIN (-3750 4625) SIG_NAME P5E_CPU0_P2_TX_DN<12>
J 0
(-3740 4635);
DISPLAY 0.659574 (-3740 4635);
PAINT MONO (-3740 4635);
DISPLAY INVISIBLE (-3740 4635);
FORCEPROP 1 LASTPIN (-3750 4625) BN 12
J 2
(-3698 4633);
DISPLAY 0.489362 (-3698 4633);
PAINT MONO (-3698 4633);
FORCEPROP 2 LAST BOM_COST IO_SLOT
J 0
(-4200 4725);
DISPLAY 0.829787 (-4200 4725);
DISPLAY INVISIBLE (-4200 4725);
FORCEPROP 2 LAST ROOM RISER1
J 0
(-4200 4675);
DISPLAY 0.829787 (-4200 4675);
PAINT RED (-4200 4675);
DISPLAY INVISIBLE (-4200 4675);
FORCEPROP 2 LAST CDS_LIB standard
J 0
(-3700 4625);
DISPLAY INVISIBLE (-3700 4625);
FORCEPROP 1 LAST BODY_TYPE PLUMBING
J 2
(-3700 4575);
DISPLAY 0.702128 (-3700 4575);
PAINT GREEN (-3700 4575);
DISPLAY INVISIBLE (-3700 4575);
FORCEPROP 1 LAST HDL_TAP TRUE
J 2
(-4025 4500);
DISPLAY 0.702128 (-4025 4500);
PAINT GREEN (-4025 4500);
DISPLAY INVISIBLE (-4025 4500);
FORCEPROP 1 LAST PATH I175
J 2
(-3698 4625);
DISPLAY 0.872340 (-3698 4625);
PAINT GREEN (-3698 4625);
DISPLAY INVISIBLE (-3698 4625);
FORCEADD TAP..6
R 2
(-3700 4525);
FORCEPROP 3 LASTPIN (-3750 4525) SIG_NAME P5E_CPU0_P2_TX_DN<13>
J 0
(-3740 4535);
DISPLAY 0.659574 (-3740 4535);
PAINT MONO (-3740 4535);
DISPLAY INVISIBLE (-3740 4535);
FORCEPROP 1 LASTPIN (-3750 4525) BN 13
J 2
(-3698 4533);
DISPLAY 0.489362 (-3698 4533);
PAINT MONO (-3698 4533);
FORCEPROP 2 LAST BOM_COST IO_SLOT
J 0
(-4200 4625);
DISPLAY 0.829787 (-4200 4625);
DISPLAY INVISIBLE (-4200 4625);
FORCEPROP 2 LAST ROOM RISER1
J 0
(-4200 4575);
DISPLAY 0.829787 (-4200 4575);
PAINT RED (-4200 4575);
DISPLAY INVISIBLE (-4200 4575);
FORCEPROP 2 LAST CDS_LIB standard
J 0
(-3700 4525);
DISPLAY INVISIBLE (-3700 4525);
FORCEPROP 1 LAST BODY_TYPE PLUMBING
J 2
(-3700 4475);
DISPLAY 0.702128 (-3700 4475);
PAINT GREEN (-3700 4475);
DISPLAY INVISIBLE (-3700 4475);
FORCEPROP 1 LAST HDL_TAP TRUE
J 2
(-4025 4400);
DISPLAY 0.702128 (-4025 4400);
PAINT GREEN (-4025 4400);
DISPLAY INVISIBLE (-4025 4400);
FORCEPROP 1 LAST PATH I176
J 2
(-3698 4525);
DISPLAY 0.872340 (-3698 4525);
PAINT GREEN (-3698 4525);
DISPLAY INVISIBLE (-3698 4525);
FORCEADD TAP..6
R 2
(-3850 4575);
FORCEPROP 3 LASTPIN (-3900 4575) SIG_NAME P5E_CPU0_P2_TX_DP<13>
J 0
(-3890 4585);
DISPLAY 0.659574 (-3890 4585);
PAINT MONO (-3890 4585);
DISPLAY INVISIBLE (-3890 4585);
FORCEPROP 1 LASTPIN (-3900 4575) BN 13
J 2
(-3848 4583);
DISPLAY 0.489362 (-3848 4583);
PAINT MONO (-3848 4583);
FORCEPROP 2 LAST BOM_COST IO_SLOT
J 0
(-4350 4675);
DISPLAY 0.829787 (-4350 4675);
DISPLAY INVISIBLE (-4350 4675);
FORCEPROP 2 LAST ROOM RISER1
J 0
(-4350 4625);
DISPLAY 0.829787 (-4350 4625);
PAINT RED (-4350 4625);
DISPLAY INVISIBLE (-4350 4625);
FORCEPROP 2 LAST CDS_LIB standard
J 0
(-3850 4575);
DISPLAY INVISIBLE (-3850 4575);
FORCEPROP 1 LAST BODY_TYPE PLUMBING
J 2
(-3850 4525);
DISPLAY 0.702128 (-3850 4525);
PAINT GREEN (-3850 4525);
DISPLAY INVISIBLE (-3850 4525);
FORCEPROP 1 LAST HDL_TAP TRUE
J 2
(-4175 4450);
DISPLAY 0.702128 (-4175 4450);
PAINT GREEN (-4175 4450);
DISPLAY INVISIBLE (-4175 4450);
FORCEPROP 1 LAST PATH I177
J 2
(-3848 4575);
DISPLAY 0.872340 (-3848 4575);
PAINT GREEN (-3848 4575);
DISPLAY INVISIBLE (-3848 4575);
FORCEADD TAP..6
R 2
(-3850 4675);
FORCEPROP 3 LASTPIN (-3900 4675) SIG_NAME P5E_CPU0_P2_TX_DP<12>
J 0
(-3890 4685);
DISPLAY 0.659574 (-3890 4685);
PAINT MONO (-3890 4685);
DISPLAY INVISIBLE (-3890 4685);
FORCEPROP 1 LASTPIN (-3900 4675) BN 12
J 2
(-3848 4683);
DISPLAY 0.489362 (-3848 4683);
PAINT MONO (-3848 4683);
FORCEPROP 2 LAST BOM_COST IO_SLOT
J 0
(-4350 4775);
DISPLAY 0.829787 (-4350 4775);
DISPLAY INVISIBLE (-4350 4775);
FORCEPROP 2 LAST ROOM RISER1
J 0
(-4350 4725);
DISPLAY 0.829787 (-4350 4725);
PAINT RED (-4350 4725);
DISPLAY INVISIBLE (-4350 4725);
FORCEPROP 2 LAST CDS_LIB standard
J 0
(-3850 4675);
DISPLAY INVISIBLE (-3850 4675);
FORCEPROP 1 LAST BODY_TYPE PLUMBING
J 2
(-3850 4625);
DISPLAY 0.702128 (-3850 4625);
PAINT GREEN (-3850 4625);
DISPLAY INVISIBLE (-3850 4625);
FORCEPROP 1 LAST HDL_TAP TRUE
J 2
(-4175 4550);
DISPLAY 0.702128 (-4175 4550);
PAINT GREEN (-4175 4550);
DISPLAY INVISIBLE (-4175 4550);
FORCEPROP 1 LAST PATH I178
J 2
(-3848 4675);
DISPLAY 0.872340 (-3848 4675);
PAINT GREEN (-3848 4675);
DISPLAY INVISIBLE (-3848 4675);
FORCEADD TAP..6
R 2
(-3850 4475);
FORCEPROP 3 LASTPIN (-3900 4475) SIG_NAME P5E_CPU0_P2_TX_DP<14>
J 0
(-3890 4485);
DISPLAY 0.659574 (-3890 4485);
PAINT MONO (-3890 4485);
DISPLAY INVISIBLE (-3890 4485);
FORCEPROP 1 LASTPIN (-3900 4475) BN 14
J 2
(-3848 4483);
DISPLAY 0.489362 (-3848 4483);
PAINT MONO (-3848 4483);
FORCEPROP 2 LAST BOM_COST IO_SLOT
J 0
(-4350 4575);
DISPLAY 0.829787 (-4350 4575);
DISPLAY INVISIBLE (-4350 4575);
FORCEPROP 2 LAST ROOM RISER1
J 0
(-4350 4525);
DISPLAY 0.829787 (-4350 4525);
PAINT RED (-4350 4525);
DISPLAY INVISIBLE (-4350 4525);
FORCEPROP 2 LAST CDS_LIB standard
J 0
(-3850 4475);
DISPLAY INVISIBLE (-3850 4475);
FORCEPROP 1 LAST BODY_TYPE PLUMBING
J 2
(-3850 4425);
DISPLAY 0.702128 (-3850 4425);
PAINT GREEN (-3850 4425);
DISPLAY INVISIBLE (-3850 4425);
FORCEPROP 1 LAST HDL_TAP TRUE
J 2
(-4175 4350);
DISPLAY 0.702128 (-4175 4350);
PAINT GREEN (-4175 4350);
DISPLAY INVISIBLE (-4175 4350);
FORCEPROP 1 LAST PATH I179
J 2
(-3848 4475);
DISPLAY 0.872340 (-3848 4475);
PAINT GREEN (-3848 4475);
DISPLAY INVISIBLE (-3848 4475);
FORCEADD TAP..6
R 2
(-3700 4325);
FORCEPROP 3 LASTPIN (-3750 4325) SIG_NAME P5E_CPU0_P2_TX_DN<15>
J 0
(-3740 4335);
DISPLAY 0.659574 (-3740 4335);
PAINT MONO (-3740 4335);
DISPLAY INVISIBLE (-3740 4335);
FORCEPROP 1 LASTPIN (-3750 4325) BN 15
J 2
(-3698 4333);
DISPLAY 0.489362 (-3698 4333);
PAINT MONO (-3698 4333);
FORCEPROP 2 LAST BOM_COST IO_SLOT
J 0
(-4200 4425);
DISPLAY 0.829787 (-4200 4425);
DISPLAY INVISIBLE (-4200 4425);
FORCEPROP 2 LAST ROOM RISER1
J 0
(-4200 4375);
DISPLAY 0.829787 (-4200 4375);
PAINT RED (-4200 4375);
DISPLAY INVISIBLE (-4200 4375);
FORCEPROP 2 LAST CDS_LIB standard
J 0
(-3700 4325);
DISPLAY INVISIBLE (-3700 4325);
FORCEPROP 1 LAST BODY_TYPE PLUMBING
J 2
(-3700 4275);
DISPLAY 0.702128 (-3700 4275);
PAINT GREEN (-3700 4275);
DISPLAY INVISIBLE (-3700 4275);
FORCEPROP 1 LAST HDL_TAP TRUE
J 2
(-4025 4200);
DISPLAY 0.702128 (-4025 4200);
PAINT GREEN (-4025 4200);
DISPLAY INVISIBLE (-4025 4200);
FORCEPROP 1 LAST PATH I180
J 2
(-3698 4325);
DISPLAY 0.872340 (-3698 4325);
PAINT GREEN (-3698 4325);
DISPLAY INVISIBLE (-3698 4325);
FORCEADD TAP..6
R 2
(-3700 4425);
FORCEPROP 3 LASTPIN (-3750 4425) SIG_NAME P5E_CPU0_P2_TX_DN<14>
J 0
(-3740 4435);
DISPLAY 0.659574 (-3740 4435);
PAINT MONO (-3740 4435);
DISPLAY INVISIBLE (-3740 4435);
FORCEPROP 1 LASTPIN (-3750 4425) BN 14
J 2
(-3698 4433);
DISPLAY 0.489362 (-3698 4433);
PAINT MONO (-3698 4433);
FORCEPROP 2 LAST BOM_COST IO_SLOT
J 0
(-4200 4525);
DISPLAY 0.829787 (-4200 4525);
DISPLAY INVISIBLE (-4200 4525);
FORCEPROP 2 LAST ROOM RISER1
J 0
(-4200 4475);
DISPLAY 0.829787 (-4200 4475);
PAINT RED (-4200 4475);
DISPLAY INVISIBLE (-4200 4475);
FORCEPROP 2 LAST CDS_LIB standard
J 0
(-3700 4425);
DISPLAY INVISIBLE (-3700 4425);
FORCEPROP 1 LAST BODY_TYPE PLUMBING
J 2
(-3700 4375);
DISPLAY 0.702128 (-3700 4375);
PAINT GREEN (-3700 4375);
DISPLAY INVISIBLE (-3700 4375);
FORCEPROP 1 LAST HDL_TAP TRUE
J 2
(-4025 4300);
DISPLAY 0.702128 (-4025 4300);
PAINT GREEN (-4025 4300);
DISPLAY INVISIBLE (-4025 4300);
FORCEPROP 1 LAST PATH I181
J 2
(-3698 4425);
DISPLAY 0.872340 (-3698 4425);
PAINT GREEN (-3698 4425);
DISPLAY INVISIBLE (-3698 4425);
FORCEADD TAP..6
R 2
(-3850 4375);
FORCEPROP 3 LASTPIN (-3900 4375) SIG_NAME P5E_CPU0_P2_TX_DP<15>
J 0
(-3890 4385);
DISPLAY 0.659574 (-3890 4385);
PAINT MONO (-3890 4385);
DISPLAY INVISIBLE (-3890 4385);
FORCEPROP 1 LASTPIN (-3900 4375) BN 15
J 2
(-3848 4383);
DISPLAY 0.489362 (-3848 4383);
PAINT MONO (-3848 4383);
FORCEPROP 2 LAST BOM_COST IO_SLOT
J 0
(-4350 4475);
DISPLAY 0.829787 (-4350 4475);
DISPLAY INVISIBLE (-4350 4475);
FORCEPROP 2 LAST ROOM RISER1
J 0
(-4350 4425);
DISPLAY 0.829787 (-4350 4425);
PAINT RED (-4350 4425);
DISPLAY INVISIBLE (-4350 4425);
FORCEPROP 2 LAST CDS_LIB standard
J 0
(-3850 4375);
DISPLAY INVISIBLE (-3850 4375);
FORCEPROP 1 LAST BODY_TYPE PLUMBING
J 2
(-3850 4325);
DISPLAY 0.702128 (-3850 4325);
PAINT GREEN (-3850 4325);
DISPLAY INVISIBLE (-3850 4325);
FORCEPROP 1 LAST HDL_TAP TRUE
J 2
(-4175 4250);
DISPLAY 0.702128 (-4175 4250);
PAINT GREEN (-4175 4250);
DISPLAY INVISIBLE (-4175 4250);
FORCEPROP 1 LAST PATH I182
J 2
(-3848 4375);
DISPLAY 0.872340 (-3848 4375);
PAINT GREEN (-3848 4375);
DISPLAY INVISIBLE (-3848 4375);
FORCEADD TAP..6
(-6300 5875);
FORCEPROP 3 LASTPIN (-6250 5875) SIG_NAME P5E_CPU0_P2_RX_DP<0>
J 0
(-6240 5885);
DISPLAY 0.659574 (-6240 5885);
PAINT MONO (-6240 5885);
DISPLAY INVISIBLE (-6240 5885);
FORCEPROP 1 LASTPIN (-6250 5875) BN 0
J 0
(-6302 5883);
DISPLAY 0.489362 (-6302 5883);
PAINT MONO (-6302 5883);
FORCEPROP 2 LAST CDS_LIB mstr_standard
J 0
(-6300 5875);
DISPLAY INVISIBLE (-6300 5875);
FORCEPROP 1 LAST BODY_TYPE PLUMBING
J 0
(-6300 5825);
DISPLAY 0.574468 (-6300 5825);
PAINT GREEN (-6300 5825);
DISPLAY INVISIBLE (-6300 5825);
FORCEPROP 1 LAST HDL_TAP TRUE
J 0
(-5975 5750);
DISPLAY 0.574468 (-5975 5750);
PAINT GREEN (-5975 5750);
DISPLAY INVISIBLE (-5975 5750);
FORCEPROP 1 LAST PATH I325
J 0
(-6302 5875);
DISPLAY 0.872340 (-6302 5875);
PAINT GREEN (-6302 5875);
DISPLAY INVISIBLE (-6302 5875);
FORCEADD TAP..6
(-6300 5675);
FORCEPROP 3 LASTPIN (-6250 5675) SIG_NAME P5E_CPU0_P2_RX_DP<2>
J 0
(-6240 5685);
DISPLAY 0.659574 (-6240 5685);
PAINT MONO (-6240 5685);
DISPLAY INVISIBLE (-6240 5685);
FORCEPROP 1 LASTPIN (-6250 5675) BN 2
J 0
(-6302 5683);
DISPLAY 0.489362 (-6302 5683);
PAINT MONO (-6302 5683);
FORCEPROP 2 LAST CDS_LIB mstr_standard
J 0
(-6300 5675);
DISPLAY INVISIBLE (-6300 5675);
FORCEPROP 1 LAST BODY_TYPE PLUMBING
J 0
(-6300 5625);
DISPLAY 0.574468 (-6300 5625);
PAINT GREEN (-6300 5625);
DISPLAY INVISIBLE (-6300 5625);
FORCEPROP 1 LAST HDL_TAP TRUE
J 0
(-5975 5550);
DISPLAY 0.574468 (-5975 5550);
PAINT GREEN (-5975 5550);
DISPLAY INVISIBLE (-5975 5550);
FORCEPROP 1 LAST PATH I326
J 0
(-6302 5675);
DISPLAY 0.872340 (-6302 5675);
PAINT GREEN (-6302 5675);
DISPLAY INVISIBLE (-6302 5675);
FORCEADD TAP..6
(-6300 5775);
FORCEPROP 3 LASTPIN (-6250 5775) SIG_NAME P5E_CPU0_P2_RX_DP<1>
J 0
(-6240 5785);
DISPLAY 0.659574 (-6240 5785);
PAINT MONO (-6240 5785);
DISPLAY INVISIBLE (-6240 5785);
FORCEPROP 1 LASTPIN (-6250 5775) BN 1
J 0
(-6302 5783);
DISPLAY 0.489362 (-6302 5783);
PAINT MONO (-6302 5783);
FORCEPROP 2 LAST CDS_LIB mstr_standard
J 0
(-6300 5775);
DISPLAY INVISIBLE (-6300 5775);
FORCEPROP 1 LAST BODY_TYPE PLUMBING
J 0
(-6300 5725);
DISPLAY 0.574468 (-6300 5725);
PAINT GREEN (-6300 5725);
DISPLAY INVISIBLE (-6300 5725);
FORCEPROP 1 LAST HDL_TAP TRUE
J 0
(-5975 5650);
DISPLAY 0.574468 (-5975 5650);
PAINT GREEN (-5975 5650);
DISPLAY INVISIBLE (-5975 5650);
FORCEPROP 1 LAST PATH I327
J 0
(-6302 5775);
DISPLAY 0.872340 (-6302 5775);
PAINT GREEN (-6302 5775);
DISPLAY INVISIBLE (-6302 5775);
FORCEADD TAP..6
(-6450 5825);
FORCEPROP 3 LASTPIN (-6400 5825) SIG_NAME P5E_CPU0_P2_RX_DN<0>
J 0
(-6390 5835);
DISPLAY 0.659574 (-6390 5835);
PAINT MONO (-6390 5835);
DISPLAY INVISIBLE (-6390 5835);
FORCEPROP 1 LASTPIN (-6400 5825) BN 0
J 0
(-6452 5833);
DISPLAY 0.489362 (-6452 5833);
PAINT MONO (-6452 5833);
FORCEPROP 2 LAST CDS_LIB mstr_standard
J 0
(-6450 5825);
DISPLAY INVISIBLE (-6450 5825);
FORCEPROP 1 LAST BODY_TYPE PLUMBING
J 0
(-6450 5775);
DISPLAY 0.574468 (-6450 5775);
PAINT GREEN (-6450 5775);
DISPLAY INVISIBLE (-6450 5775);
FORCEPROP 1 LAST HDL_TAP TRUE
J 0
(-6125 5700);
DISPLAY 0.574468 (-6125 5700);
PAINT GREEN (-6125 5700);
DISPLAY INVISIBLE (-6125 5700);
FORCEPROP 1 LAST PATH I328
J 0
(-6452 5825);
DISPLAY 0.872340 (-6452 5825);
PAINT GREEN (-6452 5825);
DISPLAY INVISIBLE (-6452 5825);
FORCEADD TAP..6
(-6450 5725);
FORCEPROP 3 LASTPIN (-6400 5725) SIG_NAME P5E_CPU0_P2_RX_DN<1>
J 0
(-6390 5735);
DISPLAY 0.659574 (-6390 5735);
PAINT MONO (-6390 5735);
DISPLAY INVISIBLE (-6390 5735);
FORCEPROP 1 LASTPIN (-6400 5725) BN 1
J 0
(-6452 5733);
DISPLAY 0.489362 (-6452 5733);
PAINT MONO (-6452 5733);
FORCEPROP 2 LAST CDS_LIB mstr_standard
J 0
(-6450 5725);
DISPLAY INVISIBLE (-6450 5725);
FORCEPROP 1 LAST BODY_TYPE PLUMBING
J 0
(-6450 5675);
DISPLAY 0.574468 (-6450 5675);
PAINT GREEN (-6450 5675);
DISPLAY INVISIBLE (-6450 5675);
FORCEPROP 1 LAST HDL_TAP TRUE
J 0
(-6125 5600);
DISPLAY 0.574468 (-6125 5600);
PAINT GREEN (-6125 5600);
DISPLAY INVISIBLE (-6125 5600);
FORCEPROP 1 LAST PATH I329
J 0
(-6452 5725);
DISPLAY 0.872340 (-6452 5725);
PAINT GREEN (-6452 5725);
DISPLAY INVISIBLE (-6452 5725);
FORCEADD TAP..6
(-6300 5575);
FORCEPROP 3 LASTPIN (-6250 5575) SIG_NAME P5E_CPU0_P2_RX_DP<3>
J 0
(-6240 5585);
DISPLAY 0.659574 (-6240 5585);
PAINT MONO (-6240 5585);
DISPLAY INVISIBLE (-6240 5585);
FORCEPROP 1 LASTPIN (-6250 5575) BN 3
J 0
(-6302 5583);
DISPLAY 0.489362 (-6302 5583);
PAINT MONO (-6302 5583);
FORCEPROP 2 LAST CDS_LIB standard
J 0
(-6300 5575);
DISPLAY INVISIBLE (-6300 5575);
FORCEPROP 1 LAST BODY_TYPE PLUMBING
J 0
(-6300 5525);
DISPLAY 0.574468 (-6300 5525);
PAINT GREEN (-6300 5525);
DISPLAY INVISIBLE (-6300 5525);
FORCEPROP 1 LAST HDL_TAP TRUE
J 0
(-5975 5450);
DISPLAY 0.574468 (-5975 5450);
PAINT GREEN (-5975 5450);
DISPLAY INVISIBLE (-5975 5450);
FORCEPROP 1 LAST PATH I330
J 0
(-6302 5575);
DISPLAY 0.872340 (-6302 5575);
PAINT GREEN (-6302 5575);
DISPLAY INVISIBLE (-6302 5575);
FORCEADD TAP..6
(-6300 5475);
FORCEPROP 3 LASTPIN (-6250 5475) SIG_NAME P5E_CPU0_P2_RX_DP<4>
J 0
(-6240 5485);
DISPLAY 0.659574 (-6240 5485);
PAINT MONO (-6240 5485);
DISPLAY INVISIBLE (-6240 5485);
FORCEPROP 1 LASTPIN (-6250 5475) BN 4
J 0
(-6302 5483);
DISPLAY 0.489362 (-6302 5483);
PAINT MONO (-6302 5483);
FORCEPROP 2 LAST CDS_LIB standard
J 0
(-6300 5475);
DISPLAY INVISIBLE (-6300 5475);
FORCEPROP 1 LAST BODY_TYPE PLUMBING
J 0
(-6300 5425);
DISPLAY 0.574468 (-6300 5425);
PAINT GREEN (-6300 5425);
DISPLAY INVISIBLE (-6300 5425);
FORCEPROP 1 LAST HDL_TAP TRUE
J 0
(-5975 5350);
DISPLAY 0.574468 (-5975 5350);
PAINT GREEN (-5975 5350);
DISPLAY INVISIBLE (-5975 5350);
FORCEPROP 1 LAST PATH I331
J 0
(-6302 5475);
DISPLAY 0.872340 (-6302 5475);
PAINT GREEN (-6302 5475);
DISPLAY INVISIBLE (-6302 5475);
FORCEADD TAP..6
(-6300 5275);
FORCEPROP 3 LASTPIN (-6250 5275) SIG_NAME P5E_CPU0_P2_RX_DP<6>
J 0
(-6240 5285);
DISPLAY 0.659574 (-6240 5285);
PAINT MONO (-6240 5285);
DISPLAY INVISIBLE (-6240 5285);
FORCEPROP 1 LASTPIN (-6250 5275) BN 6
J 0
(-6302 5283);
DISPLAY 0.489362 (-6302 5283);
PAINT MONO (-6302 5283);
FORCEPROP 2 LAST CDS_LIB standard
J 0
(-6300 5275);
DISPLAY INVISIBLE (-6300 5275);
FORCEPROP 1 LAST BODY_TYPE PLUMBING
J 0
(-6300 5225);
DISPLAY 0.574468 (-6300 5225);
PAINT GREEN (-6300 5225);
DISPLAY INVISIBLE (-6300 5225);
FORCEPROP 1 LAST HDL_TAP TRUE
J 0
(-5975 5150);
DISPLAY 0.574468 (-5975 5150);
PAINT GREEN (-5975 5150);
DISPLAY INVISIBLE (-5975 5150);
FORCEPROP 1 LAST PATH I332
J 0
(-6302 5275);
DISPLAY 0.872340 (-6302 5275);
PAINT GREEN (-6302 5275);
DISPLAY INVISIBLE (-6302 5275);
FORCEADD TAP..6
(-6300 5375);
FORCEPROP 3 LASTPIN (-6250 5375) SIG_NAME P5E_CPU0_P2_RX_DP<5>
J 0
(-6240 5385);
DISPLAY 0.659574 (-6240 5385);
PAINT MONO (-6240 5385);
DISPLAY INVISIBLE (-6240 5385);
FORCEPROP 1 LASTPIN (-6250 5375) BN 5
J 0
(-6302 5383);
DISPLAY 0.489362 (-6302 5383);
PAINT MONO (-6302 5383);
FORCEPROP 2 LAST CDS_LIB standard
J 0
(-6300 5375);
DISPLAY INVISIBLE (-6300 5375);
FORCEPROP 1 LAST BODY_TYPE PLUMBING
J 0
(-6300 5325);
DISPLAY 0.574468 (-6300 5325);
PAINT GREEN (-6300 5325);
DISPLAY INVISIBLE (-6300 5325);
FORCEPROP 1 LAST HDL_TAP TRUE
J 0
(-5975 5250);
DISPLAY 0.574468 (-5975 5250);
PAINT GREEN (-5975 5250);
DISPLAY INVISIBLE (-5975 5250);
FORCEPROP 1 LAST PATH I333
J 0
(-6302 5375);
DISPLAY 0.872340 (-6302 5375);
PAINT GREEN (-6302 5375);
DISPLAY INVISIBLE (-6302 5375);
FORCEADD TAP..6
(-6300 5175);
FORCEPROP 3 LASTPIN (-6250 5175) SIG_NAME P5E_CPU0_P2_RX_DP<7>
J 0
(-6240 5185);
DISPLAY 0.659574 (-6240 5185);
PAINT MONO (-6240 5185);
DISPLAY INVISIBLE (-6240 5185);
FORCEPROP 1 LASTPIN (-6250 5175) BN 7
J 0
(-6302 5183);
DISPLAY 0.489362 (-6302 5183);
PAINT MONO (-6302 5183);
FORCEPROP 2 LAST CDS_LIB standard
J 0
(-6300 5175);
DISPLAY INVISIBLE (-6300 5175);
FORCEPROP 1 LAST BODY_TYPE PLUMBING
J 0
(-6300 5125);
DISPLAY 0.574468 (-6300 5125);
PAINT GREEN (-6300 5125);
DISPLAY INVISIBLE (-6300 5125);
FORCEPROP 1 LAST HDL_TAP TRUE
J 0
(-5975 5050);
DISPLAY 0.574468 (-5975 5050);
PAINT GREEN (-5975 5050);
DISPLAY INVISIBLE (-5975 5050);
FORCEPROP 1 LAST PATH I334
J 0
(-6302 5175);
DISPLAY 0.872340 (-6302 5175);
PAINT GREEN (-6302 5175);
DISPLAY INVISIBLE (-6302 5175);
FORCEADD TAP..6
(-6450 5525);
FORCEPROP 3 LASTPIN (-6400 5525) SIG_NAME P5E_CPU0_P2_RX_DN<3>
J 0
(-6390 5535);
DISPLAY 0.659574 (-6390 5535);
PAINT MONO (-6390 5535);
DISPLAY INVISIBLE (-6390 5535);
FORCEPROP 1 LASTPIN (-6400 5525) BN 3
J 0
(-6452 5533);
DISPLAY 0.489362 (-6452 5533);
PAINT MONO (-6452 5533);
FORCEPROP 2 LAST CDS_LIB standard
J 0
(-6450 5525);
DISPLAY INVISIBLE (-6450 5525);
FORCEPROP 1 LAST BODY_TYPE PLUMBING
J 0
(-6450 5475);
DISPLAY 0.574468 (-6450 5475);
PAINT GREEN (-6450 5475);
DISPLAY INVISIBLE (-6450 5475);
FORCEPROP 1 LAST HDL_TAP TRUE
J 0
(-6125 5400);
DISPLAY 0.574468 (-6125 5400);
PAINT GREEN (-6125 5400);
DISPLAY INVISIBLE (-6125 5400);
FORCEPROP 1 LAST PATH I335
J 0
(-6452 5525);
DISPLAY 0.872340 (-6452 5525);
PAINT GREEN (-6452 5525);
DISPLAY INVISIBLE (-6452 5525);
FORCEADD TAP..6
(-6450 5425);
FORCEPROP 3 LASTPIN (-6400 5425) SIG_NAME P5E_CPU0_P2_RX_DN<4>
J 0
(-6390 5435);
DISPLAY 0.659574 (-6390 5435);
PAINT MONO (-6390 5435);
DISPLAY INVISIBLE (-6390 5435);
FORCEPROP 1 LASTPIN (-6400 5425) BN 4
J 0
(-6452 5433);
DISPLAY 0.489362 (-6452 5433);
PAINT MONO (-6452 5433);
FORCEPROP 2 LAST CDS_LIB standard
J 0
(-6450 5425);
DISPLAY INVISIBLE (-6450 5425);
FORCEPROP 1 LAST BODY_TYPE PLUMBING
J 0
(-6450 5375);
DISPLAY 0.574468 (-6450 5375);
PAINT GREEN (-6450 5375);
DISPLAY INVISIBLE (-6450 5375);
FORCEPROP 1 LAST HDL_TAP TRUE
J 0
(-6125 5300);
DISPLAY 0.574468 (-6125 5300);
PAINT GREEN (-6125 5300);
DISPLAY INVISIBLE (-6125 5300);
FORCEPROP 1 LAST PATH I336
J 0
(-6452 5425);
DISPLAY 0.872340 (-6452 5425);
PAINT GREEN (-6452 5425);
DISPLAY INVISIBLE (-6452 5425);
FORCEADD TAP..6
(-6450 5625);
FORCEPROP 3 LASTPIN (-6400 5625) SIG_NAME P5E_CPU0_P2_RX_DN<2>
J 0
(-6390 5635);
DISPLAY 0.659574 (-6390 5635);
PAINT MONO (-6390 5635);
DISPLAY INVISIBLE (-6390 5635);
FORCEPROP 1 LASTPIN (-6400 5625) BN 2
J 0
(-6452 5633);
DISPLAY 0.489362 (-6452 5633);
PAINT MONO (-6452 5633);
FORCEPROP 2 LAST CDS_LIB standard
J 0
(-6450 5625);
DISPLAY INVISIBLE (-6450 5625);
FORCEPROP 1 LAST BODY_TYPE PLUMBING
J 0
(-6450 5575);
DISPLAY 0.574468 (-6450 5575);
PAINT GREEN (-6450 5575);
DISPLAY INVISIBLE (-6450 5575);
FORCEPROP 1 LAST HDL_TAP TRUE
J 0
(-6125 5500);
DISPLAY 0.574468 (-6125 5500);
PAINT GREEN (-6125 5500);
DISPLAY INVISIBLE (-6125 5500);
FORCEPROP 1 LAST PATH I337
J 0
(-6452 5625);
DISPLAY 0.872340 (-6452 5625);
PAINT GREEN (-6452 5625);
DISPLAY INVISIBLE (-6452 5625);
FORCEADD TAP..6
(-6450 5325);
FORCEPROP 3 LASTPIN (-6400 5325) SIG_NAME P5E_CPU0_P2_RX_DN<5>
J 0
(-6390 5335);
DISPLAY 0.659574 (-6390 5335);
PAINT MONO (-6390 5335);
DISPLAY INVISIBLE (-6390 5335);
FORCEPROP 1 LASTPIN (-6400 5325) BN 5
J 0
(-6452 5333);
DISPLAY 0.489362 (-6452 5333);
PAINT MONO (-6452 5333);
FORCEPROP 2 LAST CDS_LIB standard
J 0
(-6450 5325);
DISPLAY INVISIBLE (-6450 5325);
FORCEPROP 1 LAST BODY_TYPE PLUMBING
J 0
(-6450 5275);
DISPLAY 0.574468 (-6450 5275);
PAINT GREEN (-6450 5275);
DISPLAY INVISIBLE (-6450 5275);
FORCEPROP 1 LAST HDL_TAP TRUE
J 0
(-6125 5200);
DISPLAY 0.574468 (-6125 5200);
PAINT GREEN (-6125 5200);
DISPLAY INVISIBLE (-6125 5200);
FORCEPROP 1 LAST PATH I338
J 0
(-6452 5325);
DISPLAY 0.872340 (-6452 5325);
PAINT GREEN (-6452 5325);
DISPLAY INVISIBLE (-6452 5325);
FORCEADD TAP..6
(-6450 5225);
FORCEPROP 3 LASTPIN (-6400 5225) SIG_NAME P5E_CPU0_P2_RX_DN<6>
J 0
(-6390 5235);
DISPLAY 0.659574 (-6390 5235);
PAINT MONO (-6390 5235);
DISPLAY INVISIBLE (-6390 5235);
FORCEPROP 1 LASTPIN (-6400 5225) BN 6
J 0
(-6452 5233);
DISPLAY 0.489362 (-6452 5233);
PAINT MONO (-6452 5233);
FORCEPROP 2 LAST CDS_LIB standard
J 0
(-6450 5225);
DISPLAY INVISIBLE (-6450 5225);
FORCEPROP 1 LAST BODY_TYPE PLUMBING
J 0
(-6450 5175);
DISPLAY 0.574468 (-6450 5175);
PAINT GREEN (-6450 5175);
DISPLAY INVISIBLE (-6450 5175);
FORCEPROP 1 LAST HDL_TAP TRUE
J 0
(-6125 5100);
DISPLAY 0.574468 (-6125 5100);
PAINT GREEN (-6125 5100);
DISPLAY INVISIBLE (-6125 5100);
FORCEPROP 1 LAST PATH I339
J 0
(-6452 5225);
DISPLAY 0.872340 (-6452 5225);
PAINT GREEN (-6452 5225);
DISPLAY INVISIBLE (-6452 5225);
FORCEADD TAP..6
(-6300 5075);
FORCEPROP 3 LASTPIN (-6250 5075) SIG_NAME P5E_CPU0_P2_RX_DP<8>
J 0
(-6240 5085);
DISPLAY 0.659574 (-6240 5085);
PAINT MONO (-6240 5085);
DISPLAY INVISIBLE (-6240 5085);
FORCEPROP 1 LASTPIN (-6250 5075) BN 8
J 0
(-6302 5083);
DISPLAY 0.489362 (-6302 5083);
PAINT MONO (-6302 5083);
FORCEPROP 2 LAST CDS_LIB standard
J 0
(-6300 5075);
DISPLAY INVISIBLE (-6300 5075);
FORCEPROP 1 LAST BODY_TYPE PLUMBING
J 0
(-6300 5025);
DISPLAY 0.574468 (-6300 5025);
PAINT GREEN (-6300 5025);
DISPLAY INVISIBLE (-6300 5025);
FORCEPROP 1 LAST HDL_TAP TRUE
J 0
(-5975 4950);
DISPLAY 0.574468 (-5975 4950);
PAINT GREEN (-5975 4950);
DISPLAY INVISIBLE (-5975 4950);
FORCEPROP 1 LAST PATH I340
J 0
(-6302 5075);
DISPLAY 0.872340 (-6302 5075);
PAINT GREEN (-6302 5075);
DISPLAY INVISIBLE (-6302 5075);
FORCEADD TAP..6
(-6300 4975);
FORCEPROP 3 LASTPIN (-6250 4975) SIG_NAME P5E_CPU0_P2_RX_DP<9>
J 0
(-6240 4985);
DISPLAY 0.659574 (-6240 4985);
PAINT MONO (-6240 4985);
DISPLAY INVISIBLE (-6240 4985);
FORCEPROP 1 LASTPIN (-6250 4975) BN 9
J 0
(-6302 4983);
DISPLAY 0.489362 (-6302 4983);
PAINT MONO (-6302 4983);
FORCEPROP 2 LAST CDS_LIB standard
J 0
(-6300 4975);
DISPLAY INVISIBLE (-6300 4975);
FORCEPROP 1 LAST BODY_TYPE PLUMBING
J 0
(-6300 4925);
DISPLAY 0.574468 (-6300 4925);
PAINT GREEN (-6300 4925);
DISPLAY INVISIBLE (-6300 4925);
FORCEPROP 1 LAST HDL_TAP TRUE
J 0
(-5975 4850);
DISPLAY 0.574468 (-5975 4850);
PAINT GREEN (-5975 4850);
DISPLAY INVISIBLE (-5975 4850);
FORCEPROP 1 LAST PATH I341
J 0
(-6302 4975);
DISPLAY 0.872340 (-6302 4975);
PAINT GREEN (-6302 4975);
DISPLAY INVISIBLE (-6302 4975);
FORCEADD TAP..6
(-6300 4875);
FORCEPROP 3 LASTPIN (-6250 4875) SIG_NAME P5E_CPU0_P2_RX_DP<10>
J 0
(-6240 4885);
DISPLAY 0.659574 (-6240 4885);
PAINT MONO (-6240 4885);
DISPLAY INVISIBLE (-6240 4885);
FORCEPROP 1 LASTPIN (-6250 4875) BN 10
J 0
(-6302 4883);
DISPLAY 0.489362 (-6302 4883);
PAINT MONO (-6302 4883);
FORCEPROP 2 LAST CDS_LIB standard
J 0
(-6300 4875);
DISPLAY INVISIBLE (-6300 4875);
FORCEPROP 1 LAST BODY_TYPE PLUMBING
J 0
(-6300 4825);
DISPLAY 0.574468 (-6300 4825);
PAINT GREEN (-6300 4825);
DISPLAY INVISIBLE (-6300 4825);
FORCEPROP 1 LAST HDL_TAP TRUE
J 0
(-5975 4750);
DISPLAY 0.574468 (-5975 4750);
PAINT GREEN (-5975 4750);
DISPLAY INVISIBLE (-5975 4750);
FORCEPROP 1 LAST PATH I342
J 0
(-6302 4875);
DISPLAY 0.872340 (-6302 4875);
PAINT GREEN (-6302 4875);
DISPLAY INVISIBLE (-6302 4875);
FORCEADD TAP..6
(-6300 4775);
FORCEPROP 3 LASTPIN (-6250 4775) SIG_NAME P5E_CPU0_P2_RX_DP<11>
J 0
(-6240 4785);
DISPLAY 0.659574 (-6240 4785);
PAINT MONO (-6240 4785);
DISPLAY INVISIBLE (-6240 4785);
FORCEPROP 1 LASTPIN (-6250 4775) BN 11
J 0
(-6302 4783);
DISPLAY 0.489362 (-6302 4783);
PAINT MONO (-6302 4783);
FORCEPROP 2 LAST CDS_LIB standard
J 0
(-6300 4775);
DISPLAY INVISIBLE (-6300 4775);
FORCEPROP 1 LAST BODY_TYPE PLUMBING
J 0
(-6300 4725);
DISPLAY 0.574468 (-6300 4725);
PAINT GREEN (-6300 4725);
DISPLAY INVISIBLE (-6300 4725);
FORCEPROP 1 LAST HDL_TAP TRUE
J 0
(-5975 4650);
DISPLAY 0.574468 (-5975 4650);
PAINT GREEN (-5975 4650);
DISPLAY INVISIBLE (-5975 4650);
FORCEPROP 1 LAST PATH I343
J 0
(-6302 4775);
DISPLAY 0.872340 (-6302 4775);
PAINT GREEN (-6302 4775);
DISPLAY INVISIBLE (-6302 4775);
FORCEADD TAP..6
(-6300 4675);
FORCEPROP 3 LASTPIN (-6250 4675) SIG_NAME P5E_CPU0_P2_RX_DP<12>
J 0
(-6240 4685);
DISPLAY 0.659574 (-6240 4685);
PAINT MONO (-6240 4685);
DISPLAY INVISIBLE (-6240 4685);
FORCEPROP 1 LASTPIN (-6250 4675) BN 12
J 0
(-6302 4683);
DISPLAY 0.489362 (-6302 4683);
PAINT MONO (-6302 4683);
FORCEPROP 2 LAST CDS_LIB standard
J 0
(-6300 4675);
DISPLAY INVISIBLE (-6300 4675);
FORCEPROP 1 LAST BODY_TYPE PLUMBING
J 0
(-6300 4625);
DISPLAY 0.574468 (-6300 4625);
PAINT GREEN (-6300 4625);
DISPLAY INVISIBLE (-6300 4625);
FORCEPROP 1 LAST HDL_TAP TRUE
J 0
(-5975 4550);
DISPLAY 0.574468 (-5975 4550);
PAINT GREEN (-5975 4550);
DISPLAY INVISIBLE (-5975 4550);
FORCEPROP 1 LAST PATH I344
J 0
(-6302 4675);
DISPLAY 0.872340 (-6302 4675);
PAINT GREEN (-6302 4675);
DISPLAY INVISIBLE (-6302 4675);
FORCEADD TAP..6
(-6450 5125);
FORCEPROP 3 LASTPIN (-6400 5125) SIG_NAME P5E_CPU0_P2_RX_DN<7>
J 0
(-6390 5135);
DISPLAY 0.659574 (-6390 5135);
PAINT MONO (-6390 5135);
DISPLAY INVISIBLE (-6390 5135);
FORCEPROP 1 LASTPIN (-6400 5125) BN 7
J 0
(-6452 5133);
DISPLAY 0.489362 (-6452 5133);
PAINT MONO (-6452 5133);
FORCEPROP 2 LAST CDS_LIB standard
J 0
(-6450 5125);
DISPLAY INVISIBLE (-6450 5125);
FORCEPROP 1 LAST BODY_TYPE PLUMBING
J 0
(-6450 5075);
DISPLAY 0.574468 (-6450 5075);
PAINT GREEN (-6450 5075);
DISPLAY INVISIBLE (-6450 5075);
FORCEPROP 1 LAST HDL_TAP TRUE
J 0
(-6125 5000);
DISPLAY 0.574468 (-6125 5000);
PAINT GREEN (-6125 5000);
DISPLAY INVISIBLE (-6125 5000);
FORCEPROP 1 LAST PATH I345
J 0
(-6452 5125);
DISPLAY 0.872340 (-6452 5125);
PAINT GREEN (-6452 5125);
DISPLAY INVISIBLE (-6452 5125);
FORCEADD TAP..6
(-6450 4925);
FORCEPROP 3 LASTPIN (-6400 4925) SIG_NAME P5E_CPU0_P2_RX_DN<9>
J 0
(-6390 4935);
DISPLAY 0.659574 (-6390 4935);
PAINT MONO (-6390 4935);
DISPLAY INVISIBLE (-6390 4935);
FORCEPROP 1 LASTPIN (-6400 4925) BN 9
J 0
(-6452 4933);
DISPLAY 0.489362 (-6452 4933);
PAINT MONO (-6452 4933);
FORCEPROP 2 LAST CDS_LIB standard
J 0
(-6450 4925);
DISPLAY INVISIBLE (-6450 4925);
FORCEPROP 1 LAST BODY_TYPE PLUMBING
J 0
(-6450 4875);
DISPLAY 0.574468 (-6450 4875);
PAINT GREEN (-6450 4875);
DISPLAY INVISIBLE (-6450 4875);
FORCEPROP 1 LAST HDL_TAP TRUE
J 0
(-6125 4800);
DISPLAY 0.574468 (-6125 4800);
PAINT GREEN (-6125 4800);
DISPLAY INVISIBLE (-6125 4800);
FORCEPROP 1 LAST PATH I346
J 0
(-6452 4925);
DISPLAY 0.872340 (-6452 4925);
PAINT GREEN (-6452 4925);
DISPLAY INVISIBLE (-6452 4925);
FORCEADD TAP..6
(-6450 5025);
FORCEPROP 3 LASTPIN (-6400 5025) SIG_NAME P5E_CPU0_P2_RX_DN<8>
J 0
(-6390 5035);
DISPLAY 0.659574 (-6390 5035);
PAINT MONO (-6390 5035);
DISPLAY INVISIBLE (-6390 5035);
FORCEPROP 1 LASTPIN (-6400 5025) BN 8
J 0
(-6452 5033);
DISPLAY 0.489362 (-6452 5033);
PAINT MONO (-6452 5033);
FORCEPROP 2 LAST CDS_LIB standard
J 0
(-6450 5025);
DISPLAY INVISIBLE (-6450 5025);
FORCEPROP 1 LAST BODY_TYPE PLUMBING
J 0
(-6450 4975);
DISPLAY 0.574468 (-6450 4975);
PAINT GREEN (-6450 4975);
DISPLAY INVISIBLE (-6450 4975);
FORCEPROP 1 LAST HDL_TAP TRUE
J 0
(-6125 4900);
DISPLAY 0.574468 (-6125 4900);
PAINT GREEN (-6125 4900);
DISPLAY INVISIBLE (-6125 4900);
FORCEPROP 1 LAST PATH I347
J 0
(-6452 5025);
DISPLAY 0.872340 (-6452 5025);
PAINT GREEN (-6452 5025);
DISPLAY INVISIBLE (-6452 5025);
FORCEADD TAP..6
(-6450 4825);
FORCEPROP 3 LASTPIN (-6400 4825) SIG_NAME P5E_CPU0_P2_RX_DN<10>
J 0
(-6390 4835);
DISPLAY 0.659574 (-6390 4835);
PAINT MONO (-6390 4835);
DISPLAY INVISIBLE (-6390 4835);
FORCEPROP 1 LASTPIN (-6400 4825) BN 10
J 0
(-6452 4833);
DISPLAY 0.489362 (-6452 4833);
PAINT MONO (-6452 4833);
FORCEPROP 2 LAST CDS_LIB standard
J 0
(-6450 4825);
DISPLAY INVISIBLE (-6450 4825);
FORCEPROP 1 LAST BODY_TYPE PLUMBING
J 0
(-6450 4775);
DISPLAY 0.574468 (-6450 4775);
PAINT GREEN (-6450 4775);
DISPLAY INVISIBLE (-6450 4775);
FORCEPROP 1 LAST HDL_TAP TRUE
J 0
(-6125 4700);
DISPLAY 0.574468 (-6125 4700);
PAINT GREEN (-6125 4700);
DISPLAY INVISIBLE (-6125 4700);
FORCEPROP 1 LAST PATH I348
J 0
(-6452 4825);
DISPLAY 0.872340 (-6452 4825);
PAINT GREEN (-6452 4825);
DISPLAY INVISIBLE (-6452 4825);
FORCEADD TAP..6
(-6450 4725);
FORCEPROP 3 LASTPIN (-6400 4725) SIG_NAME P5E_CPU0_P2_RX_DN<11>
J 0
(-6390 4735);
DISPLAY 0.659574 (-6390 4735);
PAINT MONO (-6390 4735);
DISPLAY INVISIBLE (-6390 4735);
FORCEPROP 1 LASTPIN (-6400 4725) BN 11
J 0
(-6452 4733);
DISPLAY 0.489362 (-6452 4733);
PAINT MONO (-6452 4733);
FORCEPROP 2 LAST CDS_LIB standard
J 0
(-6450 4725);
DISPLAY INVISIBLE (-6450 4725);
FORCEPROP 1 LAST BODY_TYPE PLUMBING
J 0
(-6450 4675);
DISPLAY 0.574468 (-6450 4675);
PAINT GREEN (-6450 4675);
DISPLAY INVISIBLE (-6450 4675);
FORCEPROP 1 LAST HDL_TAP TRUE
J 0
(-6125 4600);
DISPLAY 0.574468 (-6125 4600);
PAINT GREEN (-6125 4600);
DISPLAY INVISIBLE (-6125 4600);
FORCEPROP 1 LAST PATH I349
J 0
(-6452 4725);
DISPLAY 0.872340 (-6452 4725);
PAINT GREEN (-6452 4725);
DISPLAY INVISIBLE (-6452 4725);
FORCEADD TAP..6
(-6300 4575);
FORCEPROP 3 LASTPIN (-6250 4575) SIG_NAME P5E_CPU0_P2_RX_DP<13>
J 0
(-6240 4585);
DISPLAY 0.659574 (-6240 4585);
PAINT MONO (-6240 4585);
DISPLAY INVISIBLE (-6240 4585);
FORCEPROP 1 LASTPIN (-6250 4575) BN 13
J 0
(-6302 4583);
DISPLAY 0.489362 (-6302 4583);
PAINT MONO (-6302 4583);
FORCEPROP 2 LAST CDS_LIB standard
J 0
(-6300 4575);
DISPLAY INVISIBLE (-6300 4575);
FORCEPROP 1 LAST BODY_TYPE PLUMBING
J 0
(-6300 4525);
DISPLAY 0.574468 (-6300 4525);
PAINT GREEN (-6300 4525);
DISPLAY INVISIBLE (-6300 4525);
FORCEPROP 1 LAST HDL_TAP TRUE
J 0
(-5975 4450);
DISPLAY 0.574468 (-5975 4450);
PAINT GREEN (-5975 4450);
DISPLAY INVISIBLE (-5975 4450);
FORCEPROP 1 LAST PATH I350
J 0
(-6302 4575);
DISPLAY 0.872340 (-6302 4575);
PAINT GREEN (-6302 4575);
DISPLAY INVISIBLE (-6302 4575);
FORCEADD TAP..6
(-6300 4475);
FORCEPROP 3 LASTPIN (-6250 4475) SIG_NAME P5E_CPU0_P2_RX_DP<14>
J 0
(-6240 4485);
DISPLAY 0.659574 (-6240 4485);
PAINT MONO (-6240 4485);
DISPLAY INVISIBLE (-6240 4485);
FORCEPROP 1 LASTPIN (-6250 4475) BN 14
J 0
(-6302 4483);
DISPLAY 0.489362 (-6302 4483);
PAINT MONO (-6302 4483);
FORCEPROP 2 LAST CDS_LIB standard
J 0
(-6300 4475);
DISPLAY INVISIBLE (-6300 4475);
FORCEPROP 1 LAST BODY_TYPE PLUMBING
J 0
(-6300 4425);
DISPLAY 0.574468 (-6300 4425);
PAINT GREEN (-6300 4425);
DISPLAY INVISIBLE (-6300 4425);
FORCEPROP 1 LAST HDL_TAP TRUE
J 0
(-5975 4350);
DISPLAY 0.574468 (-5975 4350);
PAINT GREEN (-5975 4350);
DISPLAY INVISIBLE (-5975 4350);
FORCEPROP 1 LAST PATH I351
J 0
(-6302 4475);
DISPLAY 0.872340 (-6302 4475);
PAINT GREEN (-6302 4475);
DISPLAY INVISIBLE (-6302 4475);
FORCEADD TAP..6
(-6300 4375);
FORCEPROP 3 LASTPIN (-6250 4375) SIG_NAME P5E_CPU0_P2_RX_DP<15>
J 0
(-6240 4385);
DISPLAY 0.659574 (-6240 4385);
PAINT MONO (-6240 4385);
DISPLAY INVISIBLE (-6240 4385);
FORCEPROP 1 LASTPIN (-6250 4375) BN 15
J 0
(-6302 4383);
DISPLAY 0.489362 (-6302 4383);
PAINT MONO (-6302 4383);
FORCEPROP 2 LAST CDS_LIB standard
J 0
(-6300 4375);
DISPLAY INVISIBLE (-6300 4375);
FORCEPROP 1 LAST BODY_TYPE PLUMBING
J 0
(-6300 4325);
DISPLAY 0.574468 (-6300 4325);
PAINT GREEN (-6300 4325);
DISPLAY INVISIBLE (-6300 4325);
FORCEPROP 1 LAST HDL_TAP TRUE
J 0
(-5975 4250);
DISPLAY 0.574468 (-5975 4250);
PAINT GREEN (-5975 4250);
DISPLAY INVISIBLE (-5975 4250);
FORCEPROP 1 LAST PATH I352
J 0
(-6302 4375);
DISPLAY 0.872340 (-6302 4375);
PAINT GREEN (-6302 4375);
DISPLAY INVISIBLE (-6302 4375);
FORCEADD TAP..6
(-6450 4625);
FORCEPROP 3 LASTPIN (-6400 4625) SIG_NAME P5E_CPU0_P2_RX_DN<12>
J 0
(-6390 4635);
DISPLAY 0.659574 (-6390 4635);
PAINT MONO (-6390 4635);
DISPLAY INVISIBLE (-6390 4635);
FORCEPROP 1 LASTPIN (-6400 4625) BN 12
J 0
(-6452 4633);
DISPLAY 0.489362 (-6452 4633);
PAINT MONO (-6452 4633);
FORCEPROP 2 LAST CDS_LIB standard
J 0
(-6450 4625);
DISPLAY INVISIBLE (-6450 4625);
FORCEPROP 1 LAST BODY_TYPE PLUMBING
J 0
(-6450 4575);
DISPLAY 0.574468 (-6450 4575);
PAINT GREEN (-6450 4575);
DISPLAY INVISIBLE (-6450 4575);
FORCEPROP 1 LAST HDL_TAP TRUE
J 0
(-6125 4500);
DISPLAY 0.574468 (-6125 4500);
PAINT GREEN (-6125 4500);
DISPLAY INVISIBLE (-6125 4500);
FORCEPROP 1 LAST PATH I353
J 0
(-6452 4625);
DISPLAY 0.872340 (-6452 4625);
PAINT GREEN (-6452 4625);
DISPLAY INVISIBLE (-6452 4625);
FORCEADD TAP..6
(-6450 4425);
FORCEPROP 3 LASTPIN (-6400 4425) SIG_NAME P5E_CPU0_P2_RX_DN<14>
J 0
(-6390 4435);
DISPLAY 0.659574 (-6390 4435);
PAINT MONO (-6390 4435);
DISPLAY INVISIBLE (-6390 4435);
FORCEPROP 1 LASTPIN (-6400 4425) BN 14
J 0
(-6452 4433);
DISPLAY 0.489362 (-6452 4433);
PAINT MONO (-6452 4433);
FORCEPROP 2 LAST CDS_LIB standard
J 0
(-6450 4425);
DISPLAY INVISIBLE (-6450 4425);
FORCEPROP 1 LAST BODY_TYPE PLUMBING
J 0
(-6450 4375);
DISPLAY 0.574468 (-6450 4375);
PAINT GREEN (-6450 4375);
DISPLAY INVISIBLE (-6450 4375);
FORCEPROP 1 LAST HDL_TAP TRUE
J 0
(-6125 4300);
DISPLAY 0.574468 (-6125 4300);
PAINT GREEN (-6125 4300);
DISPLAY INVISIBLE (-6125 4300);
FORCEPROP 1 LAST PATH I354
J 0
(-6452 4425);
DISPLAY 0.872340 (-6452 4425);
PAINT GREEN (-6452 4425);
DISPLAY INVISIBLE (-6452 4425);
FORCEADD TAP..6
(-6450 4525);
FORCEPROP 3 LASTPIN (-6400 4525) SIG_NAME P5E_CPU0_P2_RX_DN<13>
J 0
(-6390 4535);
DISPLAY 0.659574 (-6390 4535);
PAINT MONO (-6390 4535);
DISPLAY INVISIBLE (-6390 4535);
FORCEPROP 1 LASTPIN (-6400 4525) BN 13
J 0
(-6452 4533);
DISPLAY 0.489362 (-6452 4533);
PAINT MONO (-6452 4533);
FORCEPROP 2 LAST CDS_LIB standard
J 0
(-6450 4525);
DISPLAY INVISIBLE (-6450 4525);
FORCEPROP 1 LAST BODY_TYPE PLUMBING
J 0
(-6450 4475);
DISPLAY 0.574468 (-6450 4475);
PAINT GREEN (-6450 4475);
DISPLAY INVISIBLE (-6450 4475);
FORCEPROP 1 LAST HDL_TAP TRUE
J 0
(-6125 4400);
DISPLAY 0.574468 (-6125 4400);
PAINT GREEN (-6125 4400);
DISPLAY INVISIBLE (-6125 4400);
FORCEPROP 1 LAST PATH I355
J 0
(-6452 4525);
DISPLAY 0.872340 (-6452 4525);
PAINT GREEN (-6452 4525);
DISPLAY INVISIBLE (-6452 4525);
FORCEADD TAP..6
(-6450 4325);
FORCEPROP 3 LASTPIN (-6400 4325) SIG_NAME P5E_CPU0_P2_RX_DN<15>
J 0
(-6390 4335);
DISPLAY 0.659574 (-6390 4335);
PAINT MONO (-6390 4335);
DISPLAY INVISIBLE (-6390 4335);
FORCEPROP 1 LASTPIN (-6400 4325) BN 15
J 0
(-6452 4333);
DISPLAY 0.489362 (-6452 4333);
PAINT MONO (-6452 4333);
FORCEPROP 2 LAST CDS_LIB standard
J 0
(-6450 4325);
DISPLAY INVISIBLE (-6450 4325);
FORCEPROP 1 LAST BODY_TYPE PLUMBING
J 0
(-6450 4275);
DISPLAY 0.574468 (-6450 4275);
PAINT GREEN (-6450 4275);
DISPLAY INVISIBLE (-6450 4275);
FORCEPROP 1 LAST HDL_TAP TRUE
J 0
(-6125 4200);
DISPLAY 0.574468 (-6125 4200);
PAINT GREEN (-6125 4200);
DISPLAY INVISIBLE (-6125 4200);
FORCEPROP 1 LAST PATH I356
J 0
(-6452 4325);
DISPLAY 0.872340 (-6452 4325);
PAINT GREEN (-6452 4325);
DISPLAY INVISIBLE (-6452 4325);
FORCEADD OFFPAGE..1
(-7475 6100);
FORCEPROP 2 LAST $XR0 296 
J 0
(-7757 6100);
DISPLAY 0.638298 (-7757 6100);
PAINT MONO (-7757 6100);
FORCEPROP 2 LAST CDS_LIB standard
J 0
(-7475 6100);
DISPLAY INVISIBLE (-7475 6100);
FORCEPROP 1 LAST OFFPAGE TRUE
J 0
(-7150 5975);
DISPLAY 0.872340 (-7150 5975);
PAINT GREEN (-7150 5975);
DISPLAY INVISIBLE (-7150 5975);
FORCEPROP 1 LAST COMMENT_BODY TRUE
J 0
(-7350 6000);
DISPLAY 0.872340 (-7350 6000);
PAINT GREEN (-7350 6000);
DISPLAY INVISIBLE (-7350 6000);
FORCEPROP 2 LAST PATH I357
J 0
(-7425 6175);
DISPLAY 1.021277 (-7425 6175);
DISPLAY INVISIBLE (-7425 6175);
FORCEADD OFFPAGE..1
(-7475 6050);
FORCEPROP 2 LAST $XR0 296 
J 0
(-7757 6050);
DISPLAY 0.638298 (-7757 6050);
PAINT MONO (-7757 6050);
FORCEPROP 2 LAST CDS_LIB standard
J 0
(-7475 6050);
DISPLAY INVISIBLE (-7475 6050);
FORCEPROP 1 LAST OFFPAGE TRUE
J 0
(-7150 5925);
DISPLAY 0.872340 (-7150 5925);
PAINT GREEN (-7150 5925);
DISPLAY INVISIBLE (-7150 5925);
FORCEPROP 1 LAST COMMENT_BODY TRUE
J 0
(-7350 5950);
DISPLAY 0.872340 (-7350 5950);
PAINT GREEN (-7350 5950);
DISPLAY INVISIBLE (-7350 5950);
FORCEPROP 2 LAST PATH I358
J 0
(-7425 6125);
DISPLAY 1.021277 (-7425 6125);
DISPLAY INVISIBLE (-7425 6125);
FORCEADD TAP..6
(-6300 2950);
FORCEPROP 3 LASTPIN (-6250 2950) SIG_NAME P5E_CPU0_P3_RX_DP<1>
J 0
(-6240 2960);
DISPLAY 0.659574 (-6240 2960);
PAINT MONO (-6240 2960);
DISPLAY INVISIBLE (-6240 2960);
FORCEPROP 1 LASTPIN (-6250 2950) BN 1
J 0
(-6302 2958);
DISPLAY 0.680851 (-6302 2958);
PAINT MONO (-6302 2958);
FORCEPROP 2 LAST CDS_LIB mstr_standard
J 0
(-6300 2950);
DISPLAY INVISIBLE (-6300 2950);
FORCEPROP 1 LAST BODY_TYPE PLUMBING
J 0
(-6300 2900);
DISPLAY 0.574468 (-6300 2900);
PAINT GREEN (-6300 2900);
DISPLAY INVISIBLE (-6300 2900);
FORCEPROP 1 LAST HDL_TAP TRUE
J 0
(-5975 2825);
DISPLAY 0.574468 (-5975 2825);
PAINT GREEN (-5975 2825);
DISPLAY INVISIBLE (-5975 2825);
FORCEPROP 1 LAST PATH I359
J 0
(-6302 2950);
DISPLAY 0.872340 (-6302 2950);
PAINT GREEN (-6302 2950);
DISPLAY INVISIBLE (-6302 2950);
FORCEADD TAP..6
(-6300 3050);
FORCEPROP 3 LASTPIN (-6250 3050) SIG_NAME P5E_CPU0_P3_RX_DP<0>
J 0
(-6240 3060);
DISPLAY 0.659574 (-6240 3060);
PAINT MONO (-6240 3060);
DISPLAY INVISIBLE (-6240 3060);
FORCEPROP 1 LASTPIN (-6250 3050) BN 0
J 0
(-6302 3058);
DISPLAY 0.680851 (-6302 3058);
PAINT MONO (-6302 3058);
FORCEPROP 2 LAST CDS_LIB mstr_standard
J 0
(-6300 3050);
DISPLAY INVISIBLE (-6300 3050);
FORCEPROP 1 LAST BODY_TYPE PLUMBING
J 0
(-6300 3000);
DISPLAY 0.574468 (-6300 3000);
PAINT GREEN (-6300 3000);
DISPLAY INVISIBLE (-6300 3000);
FORCEPROP 1 LAST HDL_TAP TRUE
J 0
(-5975 2925);
DISPLAY 0.574468 (-5975 2925);
PAINT GREEN (-5975 2925);
DISPLAY INVISIBLE (-5975 2925);
FORCEPROP 1 LAST PATH I360
J 0
(-6302 3050);
DISPLAY 0.872340 (-6302 3050);
PAINT GREEN (-6302 3050);
DISPLAY INVISIBLE (-6302 3050);
FORCEADD TAP..6
(-6300 2850);
FORCEPROP 3 LASTPIN (-6250 2850) SIG_NAME P5E_CPU0_P3_RX_DP<2>
J 0
(-6240 2860);
DISPLAY 0.659574 (-6240 2860);
PAINT MONO (-6240 2860);
DISPLAY INVISIBLE (-6240 2860);
FORCEPROP 1 LASTPIN (-6250 2850) BN 2
J 0
(-6302 2858);
DISPLAY 0.680851 (-6302 2858);
PAINT MONO (-6302 2858);
FORCEPROP 2 LAST CDS_LIB mstr_standard
J 0
(-6300 2850);
DISPLAY INVISIBLE (-6300 2850);
FORCEPROP 1 LAST BODY_TYPE PLUMBING
J 0
(-6300 2800);
DISPLAY 0.574468 (-6300 2800);
PAINT GREEN (-6300 2800);
DISPLAY INVISIBLE (-6300 2800);
FORCEPROP 1 LAST HDL_TAP TRUE
J 0
(-5975 2725);
DISPLAY 0.574468 (-5975 2725);
PAINT GREEN (-5975 2725);
DISPLAY INVISIBLE (-5975 2725);
FORCEPROP 1 LAST PATH I361
J 0
(-6302 2850);
DISPLAY 0.872340 (-6302 2850);
PAINT GREEN (-6302 2850);
DISPLAY INVISIBLE (-6302 2850);
FORCEADD TAP..6
(-6450 3000);
FORCEPROP 3 LASTPIN (-6400 3000) SIG_NAME P5E_CPU0_P3_RX_DN<0>
J 0
(-6390 3010);
DISPLAY 0.659574 (-6390 3010);
PAINT MONO (-6390 3010);
DISPLAY INVISIBLE (-6390 3010);
FORCEPROP 1 LASTPIN (-6400 3000) BN 0
J 0
(-6452 3008);
DISPLAY 0.680851 (-6452 3008);
PAINT MONO (-6452 3008);
FORCEPROP 2 LAST CDS_LIB mstr_standard
J 0
(-6450 3000);
DISPLAY INVISIBLE (-6450 3000);
FORCEPROP 1 LAST BODY_TYPE PLUMBING
J 0
(-6450 2950);
DISPLAY 0.574468 (-6450 2950);
PAINT GREEN (-6450 2950);
DISPLAY INVISIBLE (-6450 2950);
FORCEPROP 1 LAST HDL_TAP TRUE
J 0
(-6125 2875);
DISPLAY 0.574468 (-6125 2875);
PAINT GREEN (-6125 2875);
DISPLAY INVISIBLE (-6125 2875);
FORCEPROP 1 LAST PATH I362
J 0
(-6452 3000);
DISPLAY 0.872340 (-6452 3000);
PAINT GREEN (-6452 3000);
DISPLAY INVISIBLE (-6452 3000);
FORCEADD TAP..6
(-6450 2900);
FORCEPROP 3 LASTPIN (-6400 2900) SIG_NAME P5E_CPU0_P3_RX_DN<1>
J 0
(-6390 2910);
DISPLAY 0.659574 (-6390 2910);
PAINT MONO (-6390 2910);
DISPLAY INVISIBLE (-6390 2910);
FORCEPROP 1 LASTPIN (-6400 2900) BN 1
J 0
(-6452 2908);
DISPLAY 0.680851 (-6452 2908);
PAINT MONO (-6452 2908);
FORCEPROP 2 LAST CDS_LIB mstr_standard
J 0
(-6450 2900);
DISPLAY INVISIBLE (-6450 2900);
FORCEPROP 1 LAST BODY_TYPE PLUMBING
J 0
(-6450 2850);
DISPLAY 0.574468 (-6450 2850);
PAINT GREEN (-6450 2850);
DISPLAY INVISIBLE (-6450 2850);
FORCEPROP 1 LAST HDL_TAP TRUE
J 0
(-6125 2775);
DISPLAY 0.574468 (-6125 2775);
PAINT GREEN (-6125 2775);
DISPLAY INVISIBLE (-6125 2775);
FORCEPROP 1 LAST PATH I363
J 0
(-6452 2900);
DISPLAY 0.872340 (-6452 2900);
PAINT GREEN (-6452 2900);
DISPLAY INVISIBLE (-6452 2900);
FORCEADD TAP..6
(-6300 2750);
FORCEPROP 3 LASTPIN (-6250 2750) SIG_NAME P5E_CPU0_P3_RX_DP<3>
J 0
(-6240 2760);
DISPLAY 0.659574 (-6240 2760);
PAINT MONO (-6240 2760);
DISPLAY INVISIBLE (-6240 2760);
FORCEPROP 1 LASTPIN (-6250 2750) BN 3
J 0
(-6302 2758);
DISPLAY 0.680851 (-6302 2758);
PAINT MONO (-6302 2758);
FORCEPROP 2 LAST CDS_LIB standard
J 0
(-6300 2750);
DISPLAY INVISIBLE (-6300 2750);
FORCEPROP 1 LAST BODY_TYPE PLUMBING
J 0
(-6300 2700);
DISPLAY 0.574468 (-6300 2700);
PAINT GREEN (-6300 2700);
DISPLAY INVISIBLE (-6300 2700);
FORCEPROP 1 LAST HDL_TAP TRUE
J 0
(-5975 2625);
DISPLAY 0.574468 (-5975 2625);
PAINT GREEN (-5975 2625);
DISPLAY INVISIBLE (-5975 2625);
FORCEPROP 1 LAST PATH I364
J 0
(-6302 2750);
DISPLAY 0.872340 (-6302 2750);
PAINT GREEN (-6302 2750);
DISPLAY INVISIBLE (-6302 2750);
FORCEADD TAP..6
(-6300 2650);
FORCEPROP 3 LASTPIN (-6250 2650) SIG_NAME P5E_CPU0_P3_RX_DP<4>
J 0
(-6240 2660);
DISPLAY 0.659574 (-6240 2660);
PAINT MONO (-6240 2660);
DISPLAY INVISIBLE (-6240 2660);
FORCEPROP 1 LASTPIN (-6250 2650) BN 4
J 0
(-6302 2658);
DISPLAY 0.680851 (-6302 2658);
PAINT MONO (-6302 2658);
FORCEPROP 2 LAST CDS_LIB standard
J 0
(-6300 2650);
DISPLAY INVISIBLE (-6300 2650);
FORCEPROP 1 LAST BODY_TYPE PLUMBING
J 0
(-6300 2600);
DISPLAY 0.574468 (-6300 2600);
PAINT GREEN (-6300 2600);
DISPLAY INVISIBLE (-6300 2600);
FORCEPROP 1 LAST HDL_TAP TRUE
J 0
(-5975 2525);
DISPLAY 0.574468 (-5975 2525);
PAINT GREEN (-5975 2525);
DISPLAY INVISIBLE (-5975 2525);
FORCEPROP 1 LAST PATH I365
J 0
(-6302 2650);
DISPLAY 0.872340 (-6302 2650);
PAINT GREEN (-6302 2650);
DISPLAY INVISIBLE (-6302 2650);
FORCEADD TAP..6
(-6300 2550);
FORCEPROP 3 LASTPIN (-6250 2550) SIG_NAME P5E_CPU0_P3_RX_DP<5>
J 0
(-6240 2560);
DISPLAY 0.659574 (-6240 2560);
PAINT MONO (-6240 2560);
DISPLAY INVISIBLE (-6240 2560);
FORCEPROP 1 LASTPIN (-6250 2550) BN 5
J 0
(-6302 2558);
DISPLAY 0.680851 (-6302 2558);
PAINT MONO (-6302 2558);
FORCEPROP 2 LAST CDS_LIB standard
J 0
(-6300 2550);
DISPLAY INVISIBLE (-6300 2550);
FORCEPROP 1 LAST BODY_TYPE PLUMBING
J 0
(-6300 2500);
DISPLAY 0.574468 (-6300 2500);
PAINT GREEN (-6300 2500);
DISPLAY INVISIBLE (-6300 2500);
FORCEPROP 1 LAST HDL_TAP TRUE
J 0
(-5975 2425);
DISPLAY 0.574468 (-5975 2425);
PAINT GREEN (-5975 2425);
DISPLAY INVISIBLE (-5975 2425);
FORCEPROP 1 LAST PATH I366
J 0
(-6302 2550);
DISPLAY 0.872340 (-6302 2550);
PAINT GREEN (-6302 2550);
DISPLAY INVISIBLE (-6302 2550);
FORCEADD TAP..6
(-6300 2450);
FORCEPROP 3 LASTPIN (-6250 2450) SIG_NAME P5E_CPU0_P3_RX_DP<6>
J 0
(-6240 2460);
DISPLAY 0.659574 (-6240 2460);
PAINT MONO (-6240 2460);
DISPLAY INVISIBLE (-6240 2460);
FORCEPROP 1 LASTPIN (-6250 2450) BN 6
J 0
(-6302 2458);
DISPLAY 0.680851 (-6302 2458);
PAINT MONO (-6302 2458);
FORCEPROP 2 LAST CDS_LIB standard
J 0
(-6300 2450);
DISPLAY INVISIBLE (-6300 2450);
FORCEPROP 1 LAST BODY_TYPE PLUMBING
J 0
(-6300 2400);
DISPLAY 0.574468 (-6300 2400);
PAINT GREEN (-6300 2400);
DISPLAY INVISIBLE (-6300 2400);
FORCEPROP 1 LAST HDL_TAP TRUE
J 0
(-5975 2325);
DISPLAY 0.574468 (-5975 2325);
PAINT GREEN (-5975 2325);
DISPLAY INVISIBLE (-5975 2325);
FORCEPROP 1 LAST PATH I367
J 0
(-6302 2450);
DISPLAY 0.872340 (-6302 2450);
PAINT GREEN (-6302 2450);
DISPLAY INVISIBLE (-6302 2450);
FORCEADD TAP..6
(-6300 2350);
FORCEPROP 3 LASTPIN (-6250 2350) SIG_NAME P5E_CPU0_P3_RX_DP<7>
J 0
(-6240 2360);
DISPLAY 0.659574 (-6240 2360);
PAINT MONO (-6240 2360);
DISPLAY INVISIBLE (-6240 2360);
FORCEPROP 1 LASTPIN (-6250 2350) BN 7
J 0
(-6302 2358);
DISPLAY 0.680851 (-6302 2358);
PAINT MONO (-6302 2358);
FORCEPROP 2 LAST CDS_LIB standard
J 0
(-6300 2350);
DISPLAY INVISIBLE (-6300 2350);
FORCEPROP 1 LAST BODY_TYPE PLUMBING
J 0
(-6300 2300);
DISPLAY 0.574468 (-6300 2300);
PAINT GREEN (-6300 2300);
DISPLAY INVISIBLE (-6300 2300);
FORCEPROP 1 LAST HDL_TAP TRUE
J 0
(-5975 2225);
DISPLAY 0.574468 (-5975 2225);
PAINT GREEN (-5975 2225);
DISPLAY INVISIBLE (-5975 2225);
FORCEPROP 1 LAST PATH I368
J 0
(-6302 2350);
DISPLAY 0.872340 (-6302 2350);
PAINT GREEN (-6302 2350);
DISPLAY INVISIBLE (-6302 2350);
FORCEADD TAP..6
(-6450 2700);
FORCEPROP 3 LASTPIN (-6400 2700) SIG_NAME P5E_CPU0_P3_RX_DN<3>
J 0
(-6390 2710);
DISPLAY 0.659574 (-6390 2710);
PAINT MONO (-6390 2710);
DISPLAY INVISIBLE (-6390 2710);
FORCEPROP 1 LASTPIN (-6400 2700) BN 3
J 0
(-6452 2708);
DISPLAY 0.680851 (-6452 2708);
PAINT MONO (-6452 2708);
FORCEPROP 2 LAST CDS_LIB standard
J 0
(-6450 2700);
DISPLAY INVISIBLE (-6450 2700);
FORCEPROP 1 LAST BODY_TYPE PLUMBING
J 0
(-6450 2650);
DISPLAY 0.574468 (-6450 2650);
PAINT GREEN (-6450 2650);
DISPLAY INVISIBLE (-6450 2650);
FORCEPROP 1 LAST HDL_TAP TRUE
J 0
(-6125 2575);
DISPLAY 0.574468 (-6125 2575);
PAINT GREEN (-6125 2575);
DISPLAY INVISIBLE (-6125 2575);
FORCEPROP 1 LAST PATH I369
J 0
(-6452 2700);
DISPLAY 0.872340 (-6452 2700);
PAINT GREEN (-6452 2700);
DISPLAY INVISIBLE (-6452 2700);
FORCEADD TAP..6
(-6450 2800);
FORCEPROP 3 LASTPIN (-6400 2800) SIG_NAME P5E_CPU0_P3_RX_DN<2>
J 0
(-6390 2810);
DISPLAY 0.659574 (-6390 2810);
PAINT MONO (-6390 2810);
DISPLAY INVISIBLE (-6390 2810);
FORCEPROP 1 LASTPIN (-6400 2800) BN 2
J 0
(-6452 2808);
DISPLAY 0.680851 (-6452 2808);
PAINT MONO (-6452 2808);
FORCEPROP 2 LAST CDS_LIB standard
J 0
(-6450 2800);
DISPLAY INVISIBLE (-6450 2800);
FORCEPROP 1 LAST BODY_TYPE PLUMBING
J 0
(-6450 2750);
DISPLAY 0.574468 (-6450 2750);
PAINT GREEN (-6450 2750);
DISPLAY INVISIBLE (-6450 2750);
FORCEPROP 1 LAST HDL_TAP TRUE
J 0
(-6125 2675);
DISPLAY 0.574468 (-6125 2675);
PAINT GREEN (-6125 2675);
DISPLAY INVISIBLE (-6125 2675);
FORCEPROP 1 LAST PATH I370
J 0
(-6452 2800);
DISPLAY 0.872340 (-6452 2800);
PAINT GREEN (-6452 2800);
DISPLAY INVISIBLE (-6452 2800);
FORCEADD TAP..6
(-6450 2600);
FORCEPROP 3 LASTPIN (-6400 2600) SIG_NAME P5E_CPU0_P3_RX_DN<4>
J 0
(-6390 2610);
DISPLAY 0.659574 (-6390 2610);
PAINT MONO (-6390 2610);
DISPLAY INVISIBLE (-6390 2610);
FORCEPROP 1 LASTPIN (-6400 2600) BN 4
J 0
(-6452 2608);
DISPLAY 0.680851 (-6452 2608);
PAINT MONO (-6452 2608);
FORCEPROP 2 LAST CDS_LIB standard
J 0
(-6450 2600);
DISPLAY INVISIBLE (-6450 2600);
FORCEPROP 1 LAST BODY_TYPE PLUMBING
J 0
(-6450 2550);
DISPLAY 0.574468 (-6450 2550);
PAINT GREEN (-6450 2550);
DISPLAY INVISIBLE (-6450 2550);
FORCEPROP 1 LAST HDL_TAP TRUE
J 0
(-6125 2475);
DISPLAY 0.574468 (-6125 2475);
PAINT GREEN (-6125 2475);
DISPLAY INVISIBLE (-6125 2475);
FORCEPROP 1 LAST PATH I371
J 0
(-6452 2600);
DISPLAY 0.872340 (-6452 2600);
PAINT GREEN (-6452 2600);
DISPLAY INVISIBLE (-6452 2600);
FORCEADD TAP..6
(-6450 2500);
FORCEPROP 3 LASTPIN (-6400 2500) SIG_NAME P5E_CPU0_P3_RX_DN<5>
J 0
(-6390 2510);
DISPLAY 0.659574 (-6390 2510);
PAINT MONO (-6390 2510);
DISPLAY INVISIBLE (-6390 2510);
FORCEPROP 1 LASTPIN (-6400 2500) BN 5
J 0
(-6452 2508);
DISPLAY 0.680851 (-6452 2508);
PAINT MONO (-6452 2508);
FORCEPROP 2 LAST CDS_LIB standard
J 0
(-6450 2500);
DISPLAY INVISIBLE (-6450 2500);
FORCEPROP 1 LAST BODY_TYPE PLUMBING
J 0
(-6450 2450);
DISPLAY 0.574468 (-6450 2450);
PAINT GREEN (-6450 2450);
DISPLAY INVISIBLE (-6450 2450);
FORCEPROP 1 LAST HDL_TAP TRUE
J 0
(-6125 2375);
DISPLAY 0.574468 (-6125 2375);
PAINT GREEN (-6125 2375);
DISPLAY INVISIBLE (-6125 2375);
FORCEPROP 1 LAST PATH I372
J 0
(-6452 2500);
DISPLAY 0.872340 (-6452 2500);
PAINT GREEN (-6452 2500);
DISPLAY INVISIBLE (-6452 2500);
FORCEADD TAP..6
(-6450 2400);
FORCEPROP 3 LASTPIN (-6400 2400) SIG_NAME P5E_CPU0_P3_RX_DN<6>
J 0
(-6390 2410);
DISPLAY 0.659574 (-6390 2410);
PAINT MONO (-6390 2410);
DISPLAY INVISIBLE (-6390 2410);
FORCEPROP 1 LASTPIN (-6400 2400) BN 6
J 0
(-6452 2408);
DISPLAY 0.680851 (-6452 2408);
PAINT MONO (-6452 2408);
FORCEPROP 2 LAST CDS_LIB standard
J 0
(-6450 2400);
DISPLAY INVISIBLE (-6450 2400);
FORCEPROP 1 LAST BODY_TYPE PLUMBING
J 0
(-6450 2350);
DISPLAY 0.574468 (-6450 2350);
PAINT GREEN (-6450 2350);
DISPLAY INVISIBLE (-6450 2350);
FORCEPROP 1 LAST HDL_TAP TRUE
J 0
(-6125 2275);
DISPLAY 0.574468 (-6125 2275);
PAINT GREEN (-6125 2275);
DISPLAY INVISIBLE (-6125 2275);
FORCEPROP 1 LAST PATH I373
J 0
(-6452 2400);
DISPLAY 0.872340 (-6452 2400);
PAINT GREEN (-6452 2400);
DISPLAY INVISIBLE (-6452 2400);
FORCEADD TAP..6
(-6450 2300);
FORCEPROP 3 LASTPIN (-6400 2300) SIG_NAME P5E_CPU0_P3_RX_DN<7>
J 0
(-6390 2310);
DISPLAY 0.659574 (-6390 2310);
PAINT MONO (-6390 2310);
DISPLAY INVISIBLE (-6390 2310);
FORCEPROP 1 LASTPIN (-6400 2300) BN 7
J 0
(-6452 2308);
DISPLAY 0.680851 (-6452 2308);
PAINT MONO (-6452 2308);
FORCEPROP 2 LAST CDS_LIB standard
J 0
(-6450 2300);
DISPLAY INVISIBLE (-6450 2300);
FORCEPROP 1 LAST BODY_TYPE PLUMBING
J 0
(-6450 2250);
DISPLAY 0.574468 (-6450 2250);
PAINT GREEN (-6450 2250);
DISPLAY INVISIBLE (-6450 2250);
FORCEPROP 1 LAST HDL_TAP TRUE
J 0
(-6125 2175);
DISPLAY 0.574468 (-6125 2175);
PAINT GREEN (-6125 2175);
DISPLAY INVISIBLE (-6125 2175);
FORCEPROP 1 LAST PATH I374
J 0
(-6452 2300);
DISPLAY 0.872340 (-6452 2300);
PAINT GREEN (-6452 2300);
DISPLAY INVISIBLE (-6452 2300);
FORCEADD TAP..6
(-6300 2250);
FORCEPROP 3 LASTPIN (-6250 2250) SIG_NAME P5E_CPU0_P3_RX_DP<8>
J 0
(-6240 2260);
DISPLAY 0.659574 (-6240 2260);
PAINT MONO (-6240 2260);
DISPLAY INVISIBLE (-6240 2260);
FORCEPROP 1 LASTPIN (-6250 2250) BN 8
J 0
(-6302 2258);
DISPLAY 0.680851 (-6302 2258);
PAINT MONO (-6302 2258);
FORCEPROP 2 LAST CDS_LIB standard
J 0
(-6300 2250);
DISPLAY INVISIBLE (-6300 2250);
FORCEPROP 1 LAST BODY_TYPE PLUMBING
J 0
(-6300 2200);
DISPLAY 0.574468 (-6300 2200);
PAINT GREEN (-6300 2200);
DISPLAY INVISIBLE (-6300 2200);
FORCEPROP 1 LAST HDL_TAP TRUE
J 0
(-5975 2125);
DISPLAY 0.574468 (-5975 2125);
PAINT GREEN (-5975 2125);
DISPLAY INVISIBLE (-5975 2125);
FORCEPROP 1 LAST PATH I375
J 0
(-6302 2250);
DISPLAY 0.872340 (-6302 2250);
PAINT GREEN (-6302 2250);
DISPLAY INVISIBLE (-6302 2250);
FORCEADD TAP..6
(-6300 2150);
FORCEPROP 3 LASTPIN (-6250 2150) SIG_NAME P5E_CPU0_P3_RX_DP<9>
J 0
(-6240 2160);
DISPLAY 0.659574 (-6240 2160);
PAINT MONO (-6240 2160);
DISPLAY INVISIBLE (-6240 2160);
FORCEPROP 1 LASTPIN (-6250 2150) BN 9
J 0
(-6302 2158);
DISPLAY 0.680851 (-6302 2158);
PAINT MONO (-6302 2158);
FORCEPROP 2 LAST CDS_LIB standard
J 0
(-6300 2150);
DISPLAY INVISIBLE (-6300 2150);
FORCEPROP 1 LAST BODY_TYPE PLUMBING
J 0
(-6300 2100);
DISPLAY 0.574468 (-6300 2100);
PAINT GREEN (-6300 2100);
DISPLAY INVISIBLE (-6300 2100);
FORCEPROP 1 LAST HDL_TAP TRUE
J 0
(-5975 2025);
DISPLAY 0.574468 (-5975 2025);
PAINT GREEN (-5975 2025);
DISPLAY INVISIBLE (-5975 2025);
FORCEPROP 1 LAST PATH I376
J 0
(-6302 2150);
DISPLAY 0.872340 (-6302 2150);
PAINT GREEN (-6302 2150);
DISPLAY INVISIBLE (-6302 2150);
FORCEADD TAP..6
(-6300 2050);
FORCEPROP 3 LASTPIN (-6250 2050) SIG_NAME P5E_CPU0_P3_RX_DP<10>
J 0
(-6240 2060);
DISPLAY 0.659574 (-6240 2060);
PAINT MONO (-6240 2060);
DISPLAY INVISIBLE (-6240 2060);
FORCEPROP 1 LASTPIN (-6250 2050) BN 10
J 0
(-6302 2058);
DISPLAY 0.680851 (-6302 2058);
PAINT MONO (-6302 2058);
FORCEPROP 2 LAST CDS_LIB standard
J 0
(-6300 2050);
DISPLAY INVISIBLE (-6300 2050);
FORCEPROP 1 LAST BODY_TYPE PLUMBING
J 0
(-6300 2000);
DISPLAY 0.574468 (-6300 2000);
PAINT GREEN (-6300 2000);
DISPLAY INVISIBLE (-6300 2000);
FORCEPROP 1 LAST HDL_TAP TRUE
J 0
(-5975 1925);
DISPLAY 0.574468 (-5975 1925);
PAINT GREEN (-5975 1925);
DISPLAY INVISIBLE (-5975 1925);
FORCEPROP 1 LAST PATH I377
J 0
(-6302 2050);
DISPLAY 0.872340 (-6302 2050);
PAINT GREEN (-6302 2050);
DISPLAY INVISIBLE (-6302 2050);
FORCEADD TAP..6
(-6300 1950);
FORCEPROP 3 LASTPIN (-6250 1950) SIG_NAME P5E_CPU0_P3_RX_DP<11>
J 0
(-6240 1960);
DISPLAY 0.659574 (-6240 1960);
PAINT MONO (-6240 1960);
DISPLAY INVISIBLE (-6240 1960);
FORCEPROP 1 LASTPIN (-6250 1950) BN 11
J 0
(-6302 1958);
DISPLAY 0.680851 (-6302 1958);
PAINT MONO (-6302 1958);
FORCEPROP 2 LAST CDS_LIB standard
J 0
(-6300 1950);
DISPLAY INVISIBLE (-6300 1950);
FORCEPROP 1 LAST BODY_TYPE PLUMBING
J 0
(-6300 1900);
DISPLAY 0.574468 (-6300 1900);
PAINT GREEN (-6300 1900);
DISPLAY INVISIBLE (-6300 1900);
FORCEPROP 1 LAST HDL_TAP TRUE
J 0
(-5975 1825);
DISPLAY 0.574468 (-5975 1825);
PAINT GREEN (-5975 1825);
DISPLAY INVISIBLE (-5975 1825);
FORCEPROP 1 LAST PATH I378
J 0
(-6302 1950);
DISPLAY 0.872340 (-6302 1950);
PAINT GREEN (-6302 1950);
DISPLAY INVISIBLE (-6302 1950);
FORCEADD TAP..6
(-6300 1850);
FORCEPROP 3 LASTPIN (-6250 1850) SIG_NAME P5E_CPU0_P3_RX_DP<12>
J 0
(-6240 1860);
DISPLAY 0.659574 (-6240 1860);
PAINT MONO (-6240 1860);
DISPLAY INVISIBLE (-6240 1860);
FORCEPROP 1 LASTPIN (-6250 1850) BN 12
J 0
(-6302 1858);
DISPLAY 0.680851 (-6302 1858);
PAINT MONO (-6302 1858);
FORCEPROP 2 LAST CDS_LIB standard
J 0
(-6300 1850);
DISPLAY INVISIBLE (-6300 1850);
FORCEPROP 1 LAST BODY_TYPE PLUMBING
J 0
(-6300 1800);
DISPLAY 0.574468 (-6300 1800);
PAINT GREEN (-6300 1800);
DISPLAY INVISIBLE (-6300 1800);
FORCEPROP 1 LAST HDL_TAP TRUE
J 0
(-5975 1725);
DISPLAY 0.574468 (-5975 1725);
PAINT GREEN (-5975 1725);
DISPLAY INVISIBLE (-5975 1725);
FORCEPROP 1 LAST PATH I379
J 0
(-6302 1850);
DISPLAY 0.872340 (-6302 1850);
PAINT GREEN (-6302 1850);
DISPLAY INVISIBLE (-6302 1850);
FORCEADD TAP..6
(-6450 2200);
FORCEPROP 3 LASTPIN (-6400 2200) SIG_NAME P5E_CPU0_P3_RX_DN<8>
J 0
(-6390 2210);
DISPLAY 0.659574 (-6390 2210);
PAINT MONO (-6390 2210);
DISPLAY INVISIBLE (-6390 2210);
FORCEPROP 1 LASTPIN (-6400 2200) BN 8
J 0
(-6452 2208);
DISPLAY 0.680851 (-6452 2208);
PAINT MONO (-6452 2208);
FORCEPROP 2 LAST CDS_LIB standard
J 0
(-6450 2200);
DISPLAY INVISIBLE (-6450 2200);
FORCEPROP 1 LAST BODY_TYPE PLUMBING
J 0
(-6450 2150);
DISPLAY 0.574468 (-6450 2150);
PAINT GREEN (-6450 2150);
DISPLAY INVISIBLE (-6450 2150);
FORCEPROP 1 LAST HDL_TAP TRUE
J 0
(-6125 2075);
DISPLAY 0.574468 (-6125 2075);
PAINT GREEN (-6125 2075);
DISPLAY INVISIBLE (-6125 2075);
FORCEPROP 1 LAST PATH I380
J 0
(-6452 2200);
DISPLAY 0.872340 (-6452 2200);
PAINT GREEN (-6452 2200);
DISPLAY INVISIBLE (-6452 2200);
FORCEADD TAP..6
(-6450 2100);
FORCEPROP 3 LASTPIN (-6400 2100) SIG_NAME P5E_CPU0_P3_RX_DN<9>
J 0
(-6390 2110);
DISPLAY 0.659574 (-6390 2110);
PAINT MONO (-6390 2110);
DISPLAY INVISIBLE (-6390 2110);
FORCEPROP 1 LASTPIN (-6400 2100) BN 9
J 0
(-6452 2108);
DISPLAY 0.680851 (-6452 2108);
PAINT MONO (-6452 2108);
FORCEPROP 2 LAST CDS_LIB standard
J 0
(-6450 2100);
DISPLAY INVISIBLE (-6450 2100);
FORCEPROP 1 LAST BODY_TYPE PLUMBING
J 0
(-6450 2050);
DISPLAY 0.574468 (-6450 2050);
PAINT GREEN (-6450 2050);
DISPLAY INVISIBLE (-6450 2050);
FORCEPROP 1 LAST HDL_TAP TRUE
J 0
(-6125 1975);
DISPLAY 0.574468 (-6125 1975);
PAINT GREEN (-6125 1975);
DISPLAY INVISIBLE (-6125 1975);
FORCEPROP 1 LAST PATH I381
J 0
(-6452 2100);
DISPLAY 0.872340 (-6452 2100);
PAINT GREEN (-6452 2100);
DISPLAY INVISIBLE (-6452 2100);
FORCEADD TAP..6
(-6450 2000);
FORCEPROP 3 LASTPIN (-6400 2000) SIG_NAME P5E_CPU0_P3_RX_DN<10>
J 0
(-6390 2010);
DISPLAY 0.659574 (-6390 2010);
PAINT MONO (-6390 2010);
DISPLAY INVISIBLE (-6390 2010);
FORCEPROP 1 LASTPIN (-6400 2000) BN 10
J 0
(-6452 2008);
DISPLAY 0.680851 (-6452 2008);
PAINT MONO (-6452 2008);
FORCEPROP 2 LAST CDS_LIB standard
J 0
(-6450 2000);
DISPLAY INVISIBLE (-6450 2000);
FORCEPROP 1 LAST BODY_TYPE PLUMBING
J 0
(-6450 1950);
DISPLAY 0.574468 (-6450 1950);
PAINT GREEN (-6450 1950);
DISPLAY INVISIBLE (-6450 1950);
FORCEPROP 1 LAST HDL_TAP TRUE
J 0
(-6125 1875);
DISPLAY 0.574468 (-6125 1875);
PAINT GREEN (-6125 1875);
DISPLAY INVISIBLE (-6125 1875);
FORCEPROP 1 LAST PATH I382
J 0
(-6452 2000);
DISPLAY 0.872340 (-6452 2000);
PAINT GREEN (-6452 2000);
DISPLAY INVISIBLE (-6452 2000);
FORCEADD TAP..6
(-6450 1900);
FORCEPROP 3 LASTPIN (-6400 1900) SIG_NAME P5E_CPU0_P3_RX_DN<11>
J 0
(-6390 1910);
DISPLAY 0.659574 (-6390 1910);
PAINT MONO (-6390 1910);
DISPLAY INVISIBLE (-6390 1910);
FORCEPROP 1 LASTPIN (-6400 1900) BN 11
J 0
(-6452 1908);
DISPLAY 0.680851 (-6452 1908);
PAINT MONO (-6452 1908);
FORCEPROP 2 LAST CDS_LIB standard
J 0
(-6450 1900);
DISPLAY INVISIBLE (-6450 1900);
FORCEPROP 1 LAST BODY_TYPE PLUMBING
J 0
(-6450 1850);
DISPLAY 0.574468 (-6450 1850);
PAINT GREEN (-6450 1850);
DISPLAY INVISIBLE (-6450 1850);
FORCEPROP 1 LAST HDL_TAP TRUE
J 0
(-6125 1775);
DISPLAY 0.574468 (-6125 1775);
PAINT GREEN (-6125 1775);
DISPLAY INVISIBLE (-6125 1775);
FORCEPROP 1 LAST PATH I383
J 0
(-6452 1900);
DISPLAY 0.872340 (-6452 1900);
PAINT GREEN (-6452 1900);
DISPLAY INVISIBLE (-6452 1900);
FORCEADD TAP..6
(-6450 1800);
FORCEPROP 3 LASTPIN (-6400 1800) SIG_NAME P5E_CPU0_P3_RX_DN<12>
J 0
(-6390 1810);
DISPLAY 0.659574 (-6390 1810);
PAINT MONO (-6390 1810);
DISPLAY INVISIBLE (-6390 1810);
FORCEPROP 1 LASTPIN (-6400 1800) BN 12
J 0
(-6452 1808);
DISPLAY 0.680851 (-6452 1808);
PAINT MONO (-6452 1808);
FORCEPROP 2 LAST CDS_LIB standard
J 0
(-6450 1800);
DISPLAY INVISIBLE (-6450 1800);
FORCEPROP 1 LAST BODY_TYPE PLUMBING
J 0
(-6450 1750);
DISPLAY 0.574468 (-6450 1750);
PAINT GREEN (-6450 1750);
DISPLAY INVISIBLE (-6450 1750);
FORCEPROP 1 LAST HDL_TAP TRUE
J 0
(-6125 1675);
DISPLAY 0.574468 (-6125 1675);
PAINT GREEN (-6125 1675);
DISPLAY INVISIBLE (-6125 1675);
FORCEPROP 1 LAST PATH I384
J 0
(-6452 1800);
DISPLAY 0.872340 (-6452 1800);
PAINT GREEN (-6452 1800);
DISPLAY INVISIBLE (-6452 1800);
FORCEADD TAP..6
(-6300 1750);
FORCEPROP 3 LASTPIN (-6250 1750) SIG_NAME P5E_CPU0_P3_RX_DP<13>
J 0
(-6240 1760);
DISPLAY 0.659574 (-6240 1760);
PAINT MONO (-6240 1760);
DISPLAY INVISIBLE (-6240 1760);
FORCEPROP 1 LASTPIN (-6250 1750) BN 13
J 0
(-6302 1758);
DISPLAY 0.680851 (-6302 1758);
PAINT MONO (-6302 1758);
FORCEPROP 2 LAST CDS_LIB standard
J 0
(-6300 1750);
DISPLAY INVISIBLE (-6300 1750);
FORCEPROP 1 LAST BODY_TYPE PLUMBING
J 0
(-6300 1700);
DISPLAY 0.574468 (-6300 1700);
PAINT GREEN (-6300 1700);
DISPLAY INVISIBLE (-6300 1700);
FORCEPROP 1 LAST HDL_TAP TRUE
J 0
(-5975 1625);
DISPLAY 0.574468 (-5975 1625);
PAINT GREEN (-5975 1625);
DISPLAY INVISIBLE (-5975 1625);
FORCEPROP 1 LAST PATH I385
J 0
(-6302 1750);
DISPLAY 0.872340 (-6302 1750);
PAINT GREEN (-6302 1750);
DISPLAY INVISIBLE (-6302 1750);
FORCEADD TAP..6
(-6300 1550);
FORCEPROP 3 LASTPIN (-6250 1550) SIG_NAME P5E_CPU0_P3_RX_DP<15>
J 0
(-6240 1560);
DISPLAY 0.659574 (-6240 1560);
PAINT MONO (-6240 1560);
DISPLAY INVISIBLE (-6240 1560);
FORCEPROP 1 LASTPIN (-6250 1550) BN 15
J 0
(-6302 1558);
DISPLAY 0.680851 (-6302 1558);
PAINT MONO (-6302 1558);
FORCEPROP 2 LAST CDS_LIB standard
J 0
(-6300 1550);
DISPLAY INVISIBLE (-6300 1550);
FORCEPROP 1 LAST BODY_TYPE PLUMBING
J 0
(-6300 1500);
DISPLAY 0.574468 (-6300 1500);
PAINT GREEN (-6300 1500);
DISPLAY INVISIBLE (-6300 1500);
FORCEPROP 1 LAST HDL_TAP TRUE
J 0
(-5975 1425);
DISPLAY 0.574468 (-5975 1425);
PAINT GREEN (-5975 1425);
DISPLAY INVISIBLE (-5975 1425);
FORCEPROP 1 LAST PATH I386
J 0
(-6302 1550);
DISPLAY 0.872340 (-6302 1550);
PAINT GREEN (-6302 1550);
DISPLAY INVISIBLE (-6302 1550);
FORCEADD TAP..6
(-6300 1650);
FORCEPROP 3 LASTPIN (-6250 1650) SIG_NAME P5E_CPU0_P3_RX_DP<14>
J 0
(-6240 1660);
DISPLAY 0.659574 (-6240 1660);
PAINT MONO (-6240 1660);
DISPLAY INVISIBLE (-6240 1660);
FORCEPROP 1 LASTPIN (-6250 1650) BN 14
J 0
(-6302 1658);
DISPLAY 0.680851 (-6302 1658);
PAINT MONO (-6302 1658);
FORCEPROP 2 LAST CDS_LIB standard
J 0
(-6300 1650);
DISPLAY INVISIBLE (-6300 1650);
FORCEPROP 1 LAST BODY_TYPE PLUMBING
J 0
(-6300 1600);
DISPLAY 0.574468 (-6300 1600);
PAINT GREEN (-6300 1600);
DISPLAY INVISIBLE (-6300 1600);
FORCEPROP 1 LAST HDL_TAP TRUE
J 0
(-5975 1525);
DISPLAY 0.574468 (-5975 1525);
PAINT GREEN (-5975 1525);
DISPLAY INVISIBLE (-5975 1525);
FORCEPROP 1 LAST PATH I387
J 0
(-6302 1650);
DISPLAY 0.872340 (-6302 1650);
PAINT GREEN (-6302 1650);
DISPLAY INVISIBLE (-6302 1650);
FORCEADD TAP..6
(-6450 1700);
FORCEPROP 3 LASTPIN (-6400 1700) SIG_NAME P5E_CPU0_P3_RX_DN<13>
J 0
(-6390 1710);
DISPLAY 0.659574 (-6390 1710);
PAINT MONO (-6390 1710);
DISPLAY INVISIBLE (-6390 1710);
FORCEPROP 1 LASTPIN (-6400 1700) BN 13
J 0
(-6452 1708);
DISPLAY 0.680851 (-6452 1708);
PAINT MONO (-6452 1708);
FORCEPROP 2 LAST CDS_LIB standard
J 0
(-6450 1700);
DISPLAY INVISIBLE (-6450 1700);
FORCEPROP 1 LAST BODY_TYPE PLUMBING
J 0
(-6450 1650);
DISPLAY 0.574468 (-6450 1650);
PAINT GREEN (-6450 1650);
DISPLAY INVISIBLE (-6450 1650);
FORCEPROP 1 LAST HDL_TAP TRUE
J 0
(-6125 1575);
DISPLAY 0.574468 (-6125 1575);
PAINT GREEN (-6125 1575);
DISPLAY INVISIBLE (-6125 1575);
FORCEPROP 1 LAST PATH I388
J 0
(-6452 1700);
DISPLAY 0.872340 (-6452 1700);
PAINT GREEN (-6452 1700);
DISPLAY INVISIBLE (-6452 1700);
FORCEADD TAP..6
(-6450 1600);
FORCEPROP 3 LASTPIN (-6400 1600) SIG_NAME P5E_CPU0_P3_RX_DN<14>
J 0
(-6390 1610);
DISPLAY 0.659574 (-6390 1610);
PAINT MONO (-6390 1610);
DISPLAY INVISIBLE (-6390 1610);
FORCEPROP 1 LASTPIN (-6400 1600) BN 14
J 0
(-6452 1608);
DISPLAY 0.680851 (-6452 1608);
PAINT MONO (-6452 1608);
FORCEPROP 2 LAST CDS_LIB standard
J 0
(-6450 1600);
DISPLAY INVISIBLE (-6450 1600);
FORCEPROP 1 LAST BODY_TYPE PLUMBING
J 0
(-6450 1550);
DISPLAY 0.574468 (-6450 1550);
PAINT GREEN (-6450 1550);
DISPLAY INVISIBLE (-6450 1550);
FORCEPROP 1 LAST HDL_TAP TRUE
J 0
(-6125 1475);
DISPLAY 0.574468 (-6125 1475);
PAINT GREEN (-6125 1475);
DISPLAY INVISIBLE (-6125 1475);
FORCEPROP 1 LAST PATH I389
J 0
(-6452 1600);
DISPLAY 0.872340 (-6452 1600);
PAINT GREEN (-6452 1600);
DISPLAY INVISIBLE (-6452 1600);
FORCEADD TAP..6
(-6450 1500);
FORCEPROP 3 LASTPIN (-6400 1500) SIG_NAME P5E_CPU0_P3_RX_DN<15>
J 0
(-6390 1510);
DISPLAY 0.659574 (-6390 1510);
PAINT MONO (-6390 1510);
DISPLAY INVISIBLE (-6390 1510);
FORCEPROP 1 LASTPIN (-6400 1500) BN 15
J 0
(-6452 1508);
DISPLAY 0.680851 (-6452 1508);
PAINT MONO (-6452 1508);
FORCEPROP 2 LAST CDS_LIB standard
J 0
(-6450 1500);
DISPLAY INVISIBLE (-6450 1500);
FORCEPROP 1 LAST BODY_TYPE PLUMBING
J 0
(-6450 1450);
DISPLAY 0.574468 (-6450 1450);
PAINT GREEN (-6450 1450);
DISPLAY INVISIBLE (-6450 1450);
FORCEPROP 1 LAST HDL_TAP TRUE
J 0
(-6125 1375);
DISPLAY 0.574468 (-6125 1375);
PAINT GREEN (-6125 1375);
DISPLAY INVISIBLE (-6125 1375);
FORCEPROP 1 LAST PATH I390
J 0
(-6452 1500);
DISPLAY 0.872340 (-6452 1500);
PAINT GREEN (-6452 1500);
DISPLAY INVISIBLE (-6452 1500);
FORCEADD OFFPAGE..1
(-7475 3275);
FORCEPROP 2 LAST $XR0 307 
J 0
(-7757 3275);
DISPLAY 0.638298 (-7757 3275);
PAINT MONO (-7757 3275);
FORCEPROP 2 LAST CDS_LIB standard
J 0
(-7475 3275);
DISPLAY INVISIBLE (-7475 3275);
FORCEPROP 1 LAST OFFPAGE TRUE
J 0
(-7150 3150);
DISPLAY 0.872340 (-7150 3150);
PAINT GREEN (-7150 3150);
DISPLAY INVISIBLE (-7150 3150);
FORCEPROP 1 LAST COMMENT_BODY TRUE
J 0
(-7350 3175);
DISPLAY 0.872340 (-7350 3175);
PAINT GREEN (-7350 3175);
DISPLAY INVISIBLE (-7350 3175);
FORCEPROP 2 LAST PATH I391
J 0
(-7425 3350);
DISPLAY 0.680851 (-7425 3350);
DISPLAY INVISIBLE (-7425 3350);
FORCEADD OFFPAGE..1
(-7475 3225);
FORCEPROP 2 LAST $XR0 307 
J 0
(-7757 3225);
DISPLAY 0.638298 (-7757 3225);
PAINT MONO (-7757 3225);
FORCEPROP 2 LAST CDS_LIB standard
J 0
(-7475 3225);
DISPLAY INVISIBLE (-7475 3225);
FORCEPROP 1 LAST OFFPAGE TRUE
J 0
(-7150 3100);
DISPLAY 0.872340 (-7150 3100);
PAINT GREEN (-7150 3100);
DISPLAY INVISIBLE (-7150 3100);
FORCEPROP 1 LAST COMMENT_BODY TRUE
J 0
(-7350 3125);
DISPLAY 0.872340 (-7350 3125);
PAINT GREEN (-7350 3125);
DISPLAY INVISIBLE (-7350 3125);
FORCEPROP 2 LAST PATH I392
J 0
(-7425 3300);
DISPLAY 0.680851 (-7425 3300);
DISPLAY INVISIBLE (-7425 3300);
FORCEADD TAP..6
R 2
(-3700 3000);
FORCEPROP 3 LASTPIN (-3750 3000) SIG_NAME P5E_CPU0_P3_TX_DN<0>
J 0
(-3740 3010);
DISPLAY 0.659574 (-3740 3010);
PAINT MONO (-3740 3010);
DISPLAY INVISIBLE (-3740 3010);
FORCEPROP 1 LASTPIN (-3750 3000) BN 0
J 2
(-3698 3008);
DISPLAY 0.680851 (-3698 3008);
PAINT MONO (-3698 3008);
FORCEPROP 2 LAST CDS_LIB mstr_standard
J 0
(-3700 3000);
DISPLAY INVISIBLE (-3700 3000);
FORCEPROP 2 LAST BOM_COST IO_SLOT
J 0
(-4200 3100);
DISPLAY 0.829787 (-4200 3100);
DISPLAY INVISIBLE (-4200 3100);
FORCEPROP 2 LAST ROOM RISER1
J 0
(-4200 3050);
DISPLAY 0.829787 (-4200 3050);
PAINT RED (-4200 3050);
DISPLAY INVISIBLE (-4200 3050);
FORCEPROP 1 LAST BODY_TYPE PLUMBING
J 2
(-3700 2950);
DISPLAY 0.702128 (-3700 2950);
PAINT GREEN (-3700 2950);
DISPLAY INVISIBLE (-3700 2950);
FORCEPROP 1 LAST HDL_TAP TRUE
J 2
(-4025 2875);
DISPLAY 0.702128 (-4025 2875);
PAINT GREEN (-4025 2875);
DISPLAY INVISIBLE (-4025 2875);
FORCEPROP 1 LAST PATH I393
J 2
(-3698 3000);
DISPLAY 0.872340 (-3698 3000);
PAINT GREEN (-3698 3000);
DISPLAY INVISIBLE (-3698 3000);
FORCEADD TAP..6
R 2
(-3700 2900);
FORCEPROP 3 LASTPIN (-3750 2900) SIG_NAME P5E_CPU0_P3_TX_DN<1>
J 0
(-3740 2910);
DISPLAY 0.659574 (-3740 2910);
PAINT MONO (-3740 2910);
DISPLAY INVISIBLE (-3740 2910);
FORCEPROP 1 LASTPIN (-3750 2900) BN 1
J 2
(-3698 2908);
DISPLAY 0.680851 (-3698 2908);
PAINT MONO (-3698 2908);
FORCEPROP 2 LAST CDS_LIB mstr_standard
J 0
(-3700 2900);
DISPLAY INVISIBLE (-3700 2900);
FORCEPROP 2 LAST BOM_COST IO_SLOT
J 0
(-4200 3000);
DISPLAY 0.829787 (-4200 3000);
DISPLAY INVISIBLE (-4200 3000);
FORCEPROP 2 LAST ROOM RISER1
J 0
(-4200 2950);
DISPLAY 0.829787 (-4200 2950);
PAINT RED (-4200 2950);
DISPLAY INVISIBLE (-4200 2950);
FORCEPROP 1 LAST BODY_TYPE PLUMBING
J 2
(-3700 2850);
DISPLAY 0.702128 (-3700 2850);
PAINT GREEN (-3700 2850);
DISPLAY INVISIBLE (-3700 2850);
FORCEPROP 1 LAST HDL_TAP TRUE
J 2
(-4025 2775);
DISPLAY 0.702128 (-4025 2775);
PAINT GREEN (-4025 2775);
DISPLAY INVISIBLE (-4025 2775);
FORCEPROP 1 LAST PATH I394
J 2
(-3698 2900);
DISPLAY 0.872340 (-3698 2900);
PAINT GREEN (-3698 2900);
DISPLAY INVISIBLE (-3698 2900);
FORCEADD TAP..6
R 2
(-3850 2950);
FORCEPROP 3 LASTPIN (-3900 2950) SIG_NAME P5E_CPU0_P3_TX_DP<1>
J 0
(-3890 2960);
DISPLAY 0.659574 (-3890 2960);
PAINT MONO (-3890 2960);
DISPLAY INVISIBLE (-3890 2960);
FORCEPROP 1 LASTPIN (-3900 2950) BN 1
J 2
(-3848 2958);
DISPLAY 0.680851 (-3848 2958);
PAINT MONO (-3848 2958);
FORCEPROP 2 LAST CDS_LIB mstr_standard
J 0
(-3850 2950);
DISPLAY INVISIBLE (-3850 2950);
FORCEPROP 2 LAST BOM_COST IO_SLOT
J 0
(-4350 3050);
DISPLAY 0.829787 (-4350 3050);
DISPLAY INVISIBLE (-4350 3050);
FORCEPROP 2 LAST ROOM RISER1
J 0
(-4350 3000);
DISPLAY 0.829787 (-4350 3000);
PAINT RED (-4350 3000);
DISPLAY INVISIBLE (-4350 3000);
FORCEPROP 1 LAST BODY_TYPE PLUMBING
J 2
(-3850 2900);
DISPLAY 0.702128 (-3850 2900);
PAINT GREEN (-3850 2900);
DISPLAY INVISIBLE (-3850 2900);
FORCEPROP 1 LAST HDL_TAP TRUE
J 2
(-4175 2825);
DISPLAY 0.702128 (-4175 2825);
PAINT GREEN (-4175 2825);
DISPLAY INVISIBLE (-4175 2825);
FORCEPROP 1 LAST PATH I395
J 2
(-3848 2950);
DISPLAY 0.872340 (-3848 2950);
PAINT GREEN (-3848 2950);
DISPLAY INVISIBLE (-3848 2950);
FORCEADD TAP..6
R 2
(-3850 3050);
FORCEPROP 3 LASTPIN (-3900 3050) SIG_NAME P5E_CPU0_P3_TX_DP<0>
J 0
(-3890 3060);
DISPLAY 0.659574 (-3890 3060);
PAINT MONO (-3890 3060);
DISPLAY INVISIBLE (-3890 3060);
FORCEPROP 1 LASTPIN (-3900 3050) BN 0
J 2
(-3848 3058);
DISPLAY 0.680851 (-3848 3058);
PAINT MONO (-3848 3058);
FORCEPROP 2 LAST CDS_LIB mstr_standard
J 0
(-3850 3050);
DISPLAY INVISIBLE (-3850 3050);
FORCEPROP 2 LAST BOM_COST IO_SLOT
J 0
(-4350 3150);
DISPLAY 0.829787 (-4350 3150);
DISPLAY INVISIBLE (-4350 3150);
FORCEPROP 2 LAST ROOM RISER1
J 0
(-4350 3100);
DISPLAY 0.829787 (-4350 3100);
PAINT RED (-4350 3100);
DISPLAY INVISIBLE (-4350 3100);
FORCEPROP 1 LAST BODY_TYPE PLUMBING
J 2
(-3850 3000);
DISPLAY 0.702128 (-3850 3000);
PAINT GREEN (-3850 3000);
DISPLAY INVISIBLE (-3850 3000);
FORCEPROP 1 LAST HDL_TAP TRUE
J 2
(-4175 2925);
DISPLAY 0.702128 (-4175 2925);
PAINT GREEN (-4175 2925);
DISPLAY INVISIBLE (-4175 2925);
FORCEPROP 1 LAST PATH I396
J 2
(-3848 3050);
DISPLAY 0.872340 (-3848 3050);
PAINT GREEN (-3848 3050);
DISPLAY INVISIBLE (-3848 3050);
FORCEADD TAP..6
R 2
(-3850 2850);
FORCEPROP 3 LASTPIN (-3900 2850) SIG_NAME P5E_CPU0_P3_TX_DP<2>
J 0
(-3890 2860);
DISPLAY 0.659574 (-3890 2860);
PAINT MONO (-3890 2860);
DISPLAY INVISIBLE (-3890 2860);
FORCEPROP 1 LASTPIN (-3900 2850) BN 2
J 2
(-3848 2858);
DISPLAY 0.680851 (-3848 2858);
PAINT MONO (-3848 2858);
FORCEPROP 2 LAST CDS_LIB standard
J 0
(-3850 2850);
DISPLAY INVISIBLE (-3850 2850);
FORCEPROP 2 LAST BOM_COST IO_SLOT
J 0
(-4350 2950);
DISPLAY 0.829787 (-4350 2950);
DISPLAY INVISIBLE (-4350 2950);
FORCEPROP 2 LAST ROOM RISER1
J 0
(-4350 2900);
DISPLAY 0.829787 (-4350 2900);
PAINT RED (-4350 2900);
DISPLAY INVISIBLE (-4350 2900);
FORCEPROP 1 LAST BODY_TYPE PLUMBING
J 2
(-3850 2800);
DISPLAY 0.702128 (-3850 2800);
PAINT GREEN (-3850 2800);
DISPLAY INVISIBLE (-3850 2800);
FORCEPROP 1 LAST HDL_TAP TRUE
J 2
(-4175 2725);
DISPLAY 0.702128 (-4175 2725);
PAINT GREEN (-4175 2725);
DISPLAY INVISIBLE (-4175 2725);
FORCEPROP 1 LAST PATH I397
J 2
(-3848 2850);
DISPLAY 0.872340 (-3848 2850);
PAINT GREEN (-3848 2850);
DISPLAY INVISIBLE (-3848 2850);
FORCEADD TAP..6
R 2
(-3700 2700);
FORCEPROP 3 LASTPIN (-3750 2700) SIG_NAME P5E_CPU0_P3_TX_DN<3>
J 0
(-3740 2710);
DISPLAY 0.659574 (-3740 2710);
PAINT MONO (-3740 2710);
DISPLAY INVISIBLE (-3740 2710);
FORCEPROP 1 LASTPIN (-3750 2700) BN 3
J 2
(-3698 2708);
DISPLAY 0.680851 (-3698 2708);
PAINT MONO (-3698 2708);
FORCEPROP 2 LAST CDS_LIB standard
J 0
(-3700 2700);
DISPLAY INVISIBLE (-3700 2700);
FORCEPROP 2 LAST BOM_COST IO_SLOT
J 0
(-4200 2800);
DISPLAY 0.829787 (-4200 2800);
DISPLAY INVISIBLE (-4200 2800);
FORCEPROP 2 LAST ROOM RISER1
J 0
(-4200 2750);
DISPLAY 0.829787 (-4200 2750);
PAINT RED (-4200 2750);
DISPLAY INVISIBLE (-4200 2750);
FORCEPROP 1 LAST BODY_TYPE PLUMBING
J 2
(-3700 2650);
DISPLAY 0.702128 (-3700 2650);
PAINT GREEN (-3700 2650);
DISPLAY INVISIBLE (-3700 2650);
FORCEPROP 1 LAST HDL_TAP TRUE
J 2
(-4025 2575);
DISPLAY 0.702128 (-4025 2575);
PAINT GREEN (-4025 2575);
DISPLAY INVISIBLE (-4025 2575);
FORCEPROP 1 LAST PATH I398
J 2
(-3698 2700);
DISPLAY 0.872340 (-3698 2700);
PAINT GREEN (-3698 2700);
DISPLAY INVISIBLE (-3698 2700);
FORCEADD TAP..6
R 2
(-3700 2800);
FORCEPROP 3 LASTPIN (-3750 2800) SIG_NAME P5E_CPU0_P3_TX_DN<2>
J 0
(-3740 2810);
DISPLAY 0.659574 (-3740 2810);
PAINT MONO (-3740 2810);
DISPLAY INVISIBLE (-3740 2810);
FORCEPROP 1 LASTPIN (-3750 2800) BN 2
J 2
(-3698 2808);
DISPLAY 0.680851 (-3698 2808);
PAINT MONO (-3698 2808);
FORCEPROP 2 LAST CDS_LIB standard
J 0
(-3700 2800);
DISPLAY INVISIBLE (-3700 2800);
FORCEPROP 2 LAST BOM_COST IO_SLOT
J 0
(-4200 2900);
DISPLAY 0.829787 (-4200 2900);
DISPLAY INVISIBLE (-4200 2900);
FORCEPROP 2 LAST ROOM RISER1
J 0
(-4200 2850);
DISPLAY 0.829787 (-4200 2850);
PAINT RED (-4200 2850);
DISPLAY INVISIBLE (-4200 2850);
FORCEPROP 1 LAST BODY_TYPE PLUMBING
J 2
(-3700 2750);
DISPLAY 0.702128 (-3700 2750);
PAINT GREEN (-3700 2750);
DISPLAY INVISIBLE (-3700 2750);
FORCEPROP 1 LAST HDL_TAP TRUE
J 2
(-4025 2675);
DISPLAY 0.702128 (-4025 2675);
PAINT GREEN (-4025 2675);
DISPLAY INVISIBLE (-4025 2675);
FORCEPROP 1 LAST PATH I399
J 2
(-3698 2800);
DISPLAY 0.872340 (-3698 2800);
PAINT GREEN (-3698 2800);
DISPLAY INVISIBLE (-3698 2800);
FORCEADD TAP..6
R 2
(-3700 2600);
FORCEPROP 3 LASTPIN (-3750 2600) SIG_NAME P5E_CPU0_P3_TX_DN<4>
J 0
(-3740 2610);
DISPLAY 0.659574 (-3740 2610);
PAINT MONO (-3740 2610);
DISPLAY INVISIBLE (-3740 2610);
FORCEPROP 1 LASTPIN (-3750 2600) BN 4
J 2
(-3698 2608);
DISPLAY 0.680851 (-3698 2608);
PAINT MONO (-3698 2608);
FORCEPROP 2 LAST CDS_LIB standard
J 0
(-3700 2600);
DISPLAY INVISIBLE (-3700 2600);
FORCEPROP 2 LAST BOM_COST IO_SLOT
J 0
(-4200 2700);
DISPLAY 0.829787 (-4200 2700);
DISPLAY INVISIBLE (-4200 2700);
FORCEPROP 2 LAST ROOM RISER1
J 0
(-4200 2650);
DISPLAY 0.829787 (-4200 2650);
PAINT RED (-4200 2650);
DISPLAY INVISIBLE (-4200 2650);
FORCEPROP 1 LAST BODY_TYPE PLUMBING
J 2
(-3700 2550);
DISPLAY 0.702128 (-3700 2550);
PAINT GREEN (-3700 2550);
DISPLAY INVISIBLE (-3700 2550);
FORCEPROP 1 LAST HDL_TAP TRUE
J 2
(-4025 2475);
DISPLAY 0.702128 (-4025 2475);
PAINT GREEN (-4025 2475);
DISPLAY INVISIBLE (-4025 2475);
FORCEPROP 1 LAST PATH I400
J 2
(-3698 2600);
DISPLAY 0.872340 (-3698 2600);
PAINT GREEN (-3698 2600);
DISPLAY INVISIBLE (-3698 2600);
FORCEADD TAP..6
R 2
(-3700 2500);
FORCEPROP 3 LASTPIN (-3750 2500) SIG_NAME P5E_CPU0_P3_TX_DN<5>
J 0
(-3740 2510);
DISPLAY 0.659574 (-3740 2510);
PAINT MONO (-3740 2510);
DISPLAY INVISIBLE (-3740 2510);
FORCEPROP 1 LASTPIN (-3750 2500) BN 5
J 2
(-3698 2508);
DISPLAY 0.680851 (-3698 2508);
PAINT MONO (-3698 2508);
FORCEPROP 2 LAST CDS_LIB standard
J 0
(-3700 2500);
DISPLAY INVISIBLE (-3700 2500);
FORCEPROP 2 LAST ROOM RISER1
J 0
(-4200 2550);
DISPLAY 0.829787 (-4200 2550);
PAINT RED (-4200 2550);
DISPLAY INVISIBLE (-4200 2550);
FORCEPROP 2 LAST BOM_COST IO_SLOT
J 0
(-4200 2600);
DISPLAY 0.829787 (-4200 2600);
DISPLAY INVISIBLE (-4200 2600);
FORCEPROP 1 LAST BODY_TYPE PLUMBING
J 2
(-3700 2450);
DISPLAY 0.702128 (-3700 2450);
PAINT GREEN (-3700 2450);
DISPLAY INVISIBLE (-3700 2450);
FORCEPROP 1 LAST HDL_TAP TRUE
J 2
(-4025 2375);
DISPLAY 0.702128 (-4025 2375);
PAINT GREEN (-4025 2375);
DISPLAY INVISIBLE (-4025 2375);
FORCEPROP 1 LAST PATH I401
J 2
(-3698 2500);
DISPLAY 0.872340 (-3698 2500);
PAINT GREEN (-3698 2500);
DISPLAY INVISIBLE (-3698 2500);
FORCEADD TAP..6
R 2
(-3700 2300);
FORCEPROP 3 LASTPIN (-3750 2300) SIG_NAME P5E_CPU0_P3_TX_DN<7>
J 0
(-3740 2310);
DISPLAY 0.659574 (-3740 2310);
PAINT MONO (-3740 2310);
DISPLAY INVISIBLE (-3740 2310);
FORCEPROP 1 LASTPIN (-3750 2300) BN 7
J 2
(-3698 2308);
DISPLAY 0.680851 (-3698 2308);
PAINT MONO (-3698 2308);
FORCEPROP 2 LAST CDS_LIB standard
J 0
(-3700 2300);
DISPLAY INVISIBLE (-3700 2300);
FORCEPROP 2 LAST ROOM RISER1
J 0
(-4200 2350);
DISPLAY 0.829787 (-4200 2350);
PAINT RED (-4200 2350);
DISPLAY INVISIBLE (-4200 2350);
FORCEPROP 2 LAST BOM_COST IO_SLOT
J 0
(-4200 2400);
DISPLAY 0.829787 (-4200 2400);
DISPLAY INVISIBLE (-4200 2400);
FORCEPROP 1 LAST BODY_TYPE PLUMBING
J 2
(-3700 2250);
DISPLAY 0.702128 (-3700 2250);
PAINT GREEN (-3700 2250);
DISPLAY INVISIBLE (-3700 2250);
FORCEPROP 1 LAST HDL_TAP TRUE
J 2
(-4025 2175);
DISPLAY 0.702128 (-4025 2175);
PAINT GREEN (-4025 2175);
DISPLAY INVISIBLE (-4025 2175);
FORCEPROP 1 LAST PATH I402
J 2
(-3698 2300);
DISPLAY 0.872340 (-3698 2300);
PAINT GREEN (-3698 2300);
DISPLAY INVISIBLE (-3698 2300);
FORCEADD TAP..6
R 2
(-3700 2400);
FORCEPROP 3 LASTPIN (-3750 2400) SIG_NAME P5E_CPU0_P3_TX_DN<6>
J 0
(-3740 2410);
DISPLAY 0.659574 (-3740 2410);
PAINT MONO (-3740 2410);
DISPLAY INVISIBLE (-3740 2410);
FORCEPROP 1 LASTPIN (-3750 2400) BN 6
J 2
(-3698 2408);
DISPLAY 0.680851 (-3698 2408);
PAINT MONO (-3698 2408);
FORCEPROP 2 LAST CDS_LIB standard
J 0
(-3700 2400);
DISPLAY INVISIBLE (-3700 2400);
FORCEPROP 2 LAST ROOM RISER1
J 0
(-4200 2450);
DISPLAY 0.829787 (-4200 2450);
PAINT RED (-4200 2450);
DISPLAY INVISIBLE (-4200 2450);
FORCEPROP 2 LAST BOM_COST IO_SLOT
J 0
(-4200 2500);
DISPLAY 0.829787 (-4200 2500);
DISPLAY INVISIBLE (-4200 2500);
FORCEPROP 1 LAST BODY_TYPE PLUMBING
J 2
(-3700 2350);
DISPLAY 0.702128 (-3700 2350);
PAINT GREEN (-3700 2350);
DISPLAY INVISIBLE (-3700 2350);
FORCEPROP 1 LAST HDL_TAP TRUE
J 2
(-4025 2275);
DISPLAY 0.702128 (-4025 2275);
PAINT GREEN (-4025 2275);
DISPLAY INVISIBLE (-4025 2275);
FORCEPROP 1 LAST PATH I403
J 2
(-3698 2400);
DISPLAY 0.872340 (-3698 2400);
PAINT GREEN (-3698 2400);
DISPLAY INVISIBLE (-3698 2400);
FORCEADD TAP..6
R 2
(-3850 2750);
FORCEPROP 3 LASTPIN (-3900 2750) SIG_NAME P5E_CPU0_P3_TX_DP<3>
J 0
(-3890 2760);
DISPLAY 0.659574 (-3890 2760);
PAINT MONO (-3890 2760);
DISPLAY INVISIBLE (-3890 2760);
FORCEPROP 1 LASTPIN (-3900 2750) BN 3
J 2
(-3848 2758);
DISPLAY 0.680851 (-3848 2758);
PAINT MONO (-3848 2758);
FORCEPROP 2 LAST CDS_LIB standard
J 0
(-3850 2750);
DISPLAY INVISIBLE (-3850 2750);
FORCEPROP 2 LAST BOM_COST IO_SLOT
J 0
(-4350 2850);
DISPLAY 0.829787 (-4350 2850);
DISPLAY INVISIBLE (-4350 2850);
FORCEPROP 2 LAST ROOM RISER1
J 0
(-4350 2800);
DISPLAY 0.829787 (-4350 2800);
PAINT RED (-4350 2800);
DISPLAY INVISIBLE (-4350 2800);
FORCEPROP 1 LAST BODY_TYPE PLUMBING
J 2
(-3850 2700);
DISPLAY 0.702128 (-3850 2700);
PAINT GREEN (-3850 2700);
DISPLAY INVISIBLE (-3850 2700);
FORCEPROP 1 LAST HDL_TAP TRUE
J 2
(-4175 2625);
DISPLAY 0.702128 (-4175 2625);
PAINT GREEN (-4175 2625);
DISPLAY INVISIBLE (-4175 2625);
FORCEPROP 1 LAST PATH I404
J 2
(-3848 2750);
DISPLAY 0.872340 (-3848 2750);
PAINT GREEN (-3848 2750);
DISPLAY INVISIBLE (-3848 2750);
FORCEADD TAP..6
R 2
(-3850 2650);
FORCEPROP 3 LASTPIN (-3900 2650) SIG_NAME P5E_CPU0_P3_TX_DP<4>
J 0
(-3890 2660);
DISPLAY 0.659574 (-3890 2660);
PAINT MONO (-3890 2660);
DISPLAY INVISIBLE (-3890 2660);
FORCEPROP 1 LASTPIN (-3900 2650) BN 4
J 2
(-3848 2658);
DISPLAY 0.680851 (-3848 2658);
PAINT MONO (-3848 2658);
FORCEPROP 2 LAST CDS_LIB standard
J 0
(-3850 2650);
DISPLAY INVISIBLE (-3850 2650);
FORCEPROP 2 LAST BOM_COST IO_SLOT
J 0
(-4350 2750);
DISPLAY 0.829787 (-4350 2750);
DISPLAY INVISIBLE (-4350 2750);
FORCEPROP 2 LAST ROOM RISER1
J 0
(-4350 2700);
DISPLAY 0.829787 (-4350 2700);
PAINT RED (-4350 2700);
DISPLAY INVISIBLE (-4350 2700);
FORCEPROP 1 LAST BODY_TYPE PLUMBING
J 2
(-3850 2600);
DISPLAY 0.702128 (-3850 2600);
PAINT GREEN (-3850 2600);
DISPLAY INVISIBLE (-3850 2600);
FORCEPROP 1 LAST HDL_TAP TRUE
J 2
(-4175 2525);
DISPLAY 0.702128 (-4175 2525);
PAINT GREEN (-4175 2525);
DISPLAY INVISIBLE (-4175 2525);
FORCEPROP 1 LAST PATH I405
J 2
(-3848 2650);
DISPLAY 0.872340 (-3848 2650);
PAINT GREEN (-3848 2650);
DISPLAY INVISIBLE (-3848 2650);
FORCEADD TAP..6
R 2
(-3850 2450);
FORCEPROP 3 LASTPIN (-3900 2450) SIG_NAME P5E_CPU0_P3_TX_DP<6>
J 0
(-3890 2460);
DISPLAY 0.659574 (-3890 2460);
PAINT MONO (-3890 2460);
DISPLAY INVISIBLE (-3890 2460);
FORCEPROP 1 LASTPIN (-3900 2450) BN 6
J 2
(-3848 2458);
DISPLAY 0.680851 (-3848 2458);
PAINT MONO (-3848 2458);
FORCEPROP 2 LAST CDS_LIB standard
J 0
(-3850 2450);
DISPLAY INVISIBLE (-3850 2450);
FORCEPROP 2 LAST ROOM RISER1
J 0
(-4350 2500);
DISPLAY 0.829787 (-4350 2500);
PAINT RED (-4350 2500);
DISPLAY INVISIBLE (-4350 2500);
FORCEPROP 2 LAST BOM_COST IO_SLOT
J 0
(-4350 2550);
DISPLAY 0.829787 (-4350 2550);
DISPLAY INVISIBLE (-4350 2550);
FORCEPROP 1 LAST BODY_TYPE PLUMBING
J 2
(-3850 2400);
DISPLAY 0.702128 (-3850 2400);
PAINT GREEN (-3850 2400);
DISPLAY INVISIBLE (-3850 2400);
FORCEPROP 1 LAST HDL_TAP TRUE
J 2
(-4175 2325);
DISPLAY 0.702128 (-4175 2325);
PAINT GREEN (-4175 2325);
DISPLAY INVISIBLE (-4175 2325);
FORCEPROP 1 LAST PATH I406
J 2
(-3848 2450);
DISPLAY 0.872340 (-3848 2450);
PAINT GREEN (-3848 2450);
DISPLAY INVISIBLE (-3848 2450);
FORCEADD TAP..6
R 2
(-3850 2550);
FORCEPROP 3 LASTPIN (-3900 2550) SIG_NAME P5E_CPU0_P3_TX_DP<5>
J 0
(-3890 2560);
DISPLAY 0.659574 (-3890 2560);
PAINT MONO (-3890 2560);
DISPLAY INVISIBLE (-3890 2560);
FORCEPROP 1 LASTPIN (-3900 2550) BN 5
J 2
(-3848 2558);
DISPLAY 0.680851 (-3848 2558);
PAINT MONO (-3848 2558);
FORCEPROP 2 LAST CDS_LIB standard
J 0
(-3850 2550);
DISPLAY INVISIBLE (-3850 2550);
FORCEPROP 2 LAST ROOM RISER1
J 0
(-4350 2600);
DISPLAY 0.829787 (-4350 2600);
PAINT RED (-4350 2600);
DISPLAY INVISIBLE (-4350 2600);
FORCEPROP 2 LAST BOM_COST IO_SLOT
J 0
(-4350 2650);
DISPLAY 0.829787 (-4350 2650);
DISPLAY INVISIBLE (-4350 2650);
FORCEPROP 1 LAST BODY_TYPE PLUMBING
J 2
(-3850 2500);
DISPLAY 0.702128 (-3850 2500);
PAINT GREEN (-3850 2500);
DISPLAY INVISIBLE (-3850 2500);
FORCEPROP 1 LAST HDL_TAP TRUE
J 2
(-4175 2425);
DISPLAY 0.702128 (-4175 2425);
PAINT GREEN (-4175 2425);
DISPLAY INVISIBLE (-4175 2425);
FORCEPROP 1 LAST PATH I407
J 2
(-3848 2550);
DISPLAY 0.872340 (-3848 2550);
PAINT GREEN (-3848 2550);
DISPLAY INVISIBLE (-3848 2550);
FORCEADD TAP..6
R 2
(-3850 2350);
FORCEPROP 3 LASTPIN (-3900 2350) SIG_NAME P5E_CPU0_P3_TX_DP<7>
J 0
(-3890 2360);
DISPLAY 0.659574 (-3890 2360);
PAINT MONO (-3890 2360);
DISPLAY INVISIBLE (-3890 2360);
FORCEPROP 1 LASTPIN (-3900 2350) BN 7
J 2
(-3848 2358);
DISPLAY 0.680851 (-3848 2358);
PAINT MONO (-3848 2358);
FORCEPROP 2 LAST CDS_LIB standard
J 0
(-3850 2350);
DISPLAY INVISIBLE (-3850 2350);
FORCEPROP 2 LAST ROOM RISER1
J 0
(-4350 2400);
DISPLAY 0.829787 (-4350 2400);
PAINT RED (-4350 2400);
DISPLAY INVISIBLE (-4350 2400);
FORCEPROP 2 LAST BOM_COST IO_SLOT
J 0
(-4350 2450);
DISPLAY 0.829787 (-4350 2450);
DISPLAY INVISIBLE (-4350 2450);
FORCEPROP 1 LAST BODY_TYPE PLUMBING
J 2
(-3850 2300);
DISPLAY 0.702128 (-3850 2300);
PAINT GREEN (-3850 2300);
DISPLAY INVISIBLE (-3850 2300);
FORCEPROP 1 LAST HDL_TAP TRUE
J 2
(-4175 2225);
DISPLAY 0.702128 (-4175 2225);
PAINT GREEN (-4175 2225);
DISPLAY INVISIBLE (-4175 2225);
FORCEPROP 1 LAST PATH I408
J 2
(-3848 2350);
DISPLAY 0.872340 (-3848 2350);
PAINT GREEN (-3848 2350);
DISPLAY INVISIBLE (-3848 2350);
FORCEADD TAP..6
R 2
(-3700 2100);
FORCEPROP 3 LASTPIN (-3750 2100) SIG_NAME P5E_CPU0_P3_TX_DN<9>
J 0
(-3740 2110);
DISPLAY 0.659574 (-3740 2110);
PAINT MONO (-3740 2110);
DISPLAY INVISIBLE (-3740 2110);
FORCEPROP 1 LASTPIN (-3750 2100) BN 9
J 2
(-3698 2108);
DISPLAY 0.680851 (-3698 2108);
PAINT MONO (-3698 2108);
FORCEPROP 2 LAST CDS_LIB standard
J 0
(-3700 2100);
DISPLAY INVISIBLE (-3700 2100);
FORCEPROP 2 LAST ROOM RISER1
J 0
(-4200 2150);
DISPLAY 0.829787 (-4200 2150);
PAINT RED (-4200 2150);
DISPLAY INVISIBLE (-4200 2150);
FORCEPROP 2 LAST BOM_COST IO_SLOT
J 0
(-4200 2200);
DISPLAY 0.829787 (-4200 2200);
DISPLAY INVISIBLE (-4200 2200);
FORCEPROP 1 LAST BODY_TYPE PLUMBING
J 2
(-3700 2050);
DISPLAY 0.702128 (-3700 2050);
PAINT GREEN (-3700 2050);
DISPLAY INVISIBLE (-3700 2050);
FORCEPROP 1 LAST HDL_TAP TRUE
J 2
(-4025 1975);
DISPLAY 0.702128 (-4025 1975);
PAINT GREEN (-4025 1975);
DISPLAY INVISIBLE (-4025 1975);
FORCEPROP 1 LAST PATH I409
J 2
(-3698 2100);
DISPLAY 0.872340 (-3698 2100);
PAINT GREEN (-3698 2100);
DISPLAY INVISIBLE (-3698 2100);
FORCEADD TAP..6
R 2
(-3700 2200);
FORCEPROP 3 LASTPIN (-3750 2200) SIG_NAME P5E_CPU0_P3_TX_DN<8>
J 0
(-3740 2210);
DISPLAY 0.659574 (-3740 2210);
PAINT MONO (-3740 2210);
DISPLAY INVISIBLE (-3740 2210);
FORCEPROP 1 LASTPIN (-3750 2200) BN 8
J 2
(-3698 2208);
DISPLAY 0.680851 (-3698 2208);
PAINT MONO (-3698 2208);
FORCEPROP 2 LAST CDS_LIB standard
J 0
(-3700 2200);
DISPLAY INVISIBLE (-3700 2200);
FORCEPROP 2 LAST ROOM RISER1
J 0
(-4200 2250);
DISPLAY 0.829787 (-4200 2250);
PAINT RED (-4200 2250);
DISPLAY INVISIBLE (-4200 2250);
FORCEPROP 2 LAST BOM_COST IO_SLOT
J 0
(-4200 2300);
DISPLAY 0.829787 (-4200 2300);
DISPLAY INVISIBLE (-4200 2300);
FORCEPROP 1 LAST BODY_TYPE PLUMBING
J 2
(-3700 2150);
DISPLAY 0.702128 (-3700 2150);
PAINT GREEN (-3700 2150);
DISPLAY INVISIBLE (-3700 2150);
FORCEPROP 1 LAST HDL_TAP TRUE
J 2
(-4025 2075);
DISPLAY 0.702128 (-4025 2075);
PAINT GREEN (-4025 2075);
DISPLAY INVISIBLE (-4025 2075);
FORCEPROP 1 LAST PATH I410
J 2
(-3698 2200);
DISPLAY 0.872340 (-3698 2200);
PAINT GREEN (-3698 2200);
DISPLAY INVISIBLE (-3698 2200);
FORCEADD TAP..6
R 2
(-3700 2000);
FORCEPROP 3 LASTPIN (-3750 2000) SIG_NAME P5E_CPU0_P3_TX_DN<10>
J 0
(-3740 2010);
DISPLAY 0.659574 (-3740 2010);
PAINT MONO (-3740 2010);
DISPLAY INVISIBLE (-3740 2010);
FORCEPROP 1 LASTPIN (-3750 2000) BN 10
J 2
(-3698 2008);
DISPLAY 0.680851 (-3698 2008);
PAINT MONO (-3698 2008);
FORCEPROP 2 LAST CDS_LIB standard
J 0
(-3700 2000);
DISPLAY INVISIBLE (-3700 2000);
FORCEPROP 2 LAST ROOM RISER1
J 0
(-4200 2050);
DISPLAY 0.829787 (-4200 2050);
PAINT RED (-4200 2050);
DISPLAY INVISIBLE (-4200 2050);
FORCEPROP 2 LAST BOM_COST IO_SLOT
J 0
(-4200 2100);
DISPLAY 0.829787 (-4200 2100);
DISPLAY INVISIBLE (-4200 2100);
FORCEPROP 1 LAST BODY_TYPE PLUMBING
J 2
(-3700 1950);
DISPLAY 0.702128 (-3700 1950);
PAINT GREEN (-3700 1950);
DISPLAY INVISIBLE (-3700 1950);
FORCEPROP 1 LAST HDL_TAP TRUE
J 2
(-4025 1875);
DISPLAY 0.702128 (-4025 1875);
PAINT GREEN (-4025 1875);
DISPLAY INVISIBLE (-4025 1875);
FORCEPROP 1 LAST PATH I411
J 2
(-3698 2000);
DISPLAY 0.872340 (-3698 2000);
PAINT GREEN (-3698 2000);
DISPLAY INVISIBLE (-3698 2000);
FORCEADD TAP..6
R 2
(-3700 1800);
FORCEPROP 3 LASTPIN (-3750 1800) SIG_NAME P5E_CPU0_P3_TX_DN<12>
J 0
(-3740 1810);
DISPLAY 0.659574 (-3740 1810);
PAINT MONO (-3740 1810);
DISPLAY INVISIBLE (-3740 1810);
FORCEPROP 1 LASTPIN (-3750 1800) BN 12
J 2
(-3698 1808);
DISPLAY 0.680851 (-3698 1808);
PAINT MONO (-3698 1808);
FORCEPROP 2 LAST CDS_LIB standard
J 0
(-3700 1800);
DISPLAY INVISIBLE (-3700 1800);
FORCEPROP 2 LAST ROOM RISER1
J 0
(-4200 1850);
DISPLAY 0.829787 (-4200 1850);
PAINT RED (-4200 1850);
DISPLAY INVISIBLE (-4200 1850);
FORCEPROP 2 LAST BOM_COST IO_SLOT
J 0
(-4200 1900);
DISPLAY 0.829787 (-4200 1900);
DISPLAY INVISIBLE (-4200 1900);
FORCEPROP 1 LAST BODY_TYPE PLUMBING
J 2
(-3700 1750);
DISPLAY 0.702128 (-3700 1750);
PAINT GREEN (-3700 1750);
DISPLAY INVISIBLE (-3700 1750);
FORCEPROP 1 LAST HDL_TAP TRUE
J 2
(-4025 1675);
DISPLAY 0.702128 (-4025 1675);
PAINT GREEN (-4025 1675);
DISPLAY INVISIBLE (-4025 1675);
FORCEPROP 1 LAST PATH I412
J 2
(-3698 1800);
DISPLAY 0.872340 (-3698 1800);
PAINT GREEN (-3698 1800);
DISPLAY INVISIBLE (-3698 1800);
FORCEADD TAP..6
R 2
(-3700 1900);
FORCEPROP 3 LASTPIN (-3750 1900) SIG_NAME P5E_CPU0_P3_TX_DN<11>
J 0
(-3740 1910);
DISPLAY 0.659574 (-3740 1910);
PAINT MONO (-3740 1910);
DISPLAY INVISIBLE (-3740 1910);
FORCEPROP 1 LASTPIN (-3750 1900) BN 11
J 2
(-3698 1908);
DISPLAY 0.680851 (-3698 1908);
PAINT MONO (-3698 1908);
FORCEPROP 2 LAST CDS_LIB standard
J 0
(-3700 1900);
DISPLAY INVISIBLE (-3700 1900);
FORCEPROP 2 LAST ROOM RISER1
J 0
(-4200 1950);
DISPLAY 0.829787 (-4200 1950);
PAINT RED (-4200 1950);
DISPLAY INVISIBLE (-4200 1950);
FORCEPROP 2 LAST BOM_COST IO_SLOT
J 0
(-4200 2000);
DISPLAY 0.829787 (-4200 2000);
DISPLAY INVISIBLE (-4200 2000);
FORCEPROP 1 LAST BODY_TYPE PLUMBING
J 2
(-3700 1850);
DISPLAY 0.702128 (-3700 1850);
PAINT GREEN (-3700 1850);
DISPLAY INVISIBLE (-3700 1850);
FORCEPROP 1 LAST HDL_TAP TRUE
J 2
(-4025 1775);
DISPLAY 0.702128 (-4025 1775);
PAINT GREEN (-4025 1775);
DISPLAY INVISIBLE (-4025 1775);
FORCEPROP 1 LAST PATH I413
J 2
(-3698 1900);
DISPLAY 0.872340 (-3698 1900);
PAINT GREEN (-3698 1900);
DISPLAY INVISIBLE (-3698 1900);
FORCEADD TAP..6
R 2
(-3850 2250);
FORCEPROP 3 LASTPIN (-3900 2250) SIG_NAME P5E_CPU0_P3_TX_DP<8>
J 0
(-3890 2260);
DISPLAY 0.659574 (-3890 2260);
PAINT MONO (-3890 2260);
DISPLAY INVISIBLE (-3890 2260);
FORCEPROP 1 LASTPIN (-3900 2250) BN 8
J 2
(-3848 2258);
DISPLAY 0.680851 (-3848 2258);
PAINT MONO (-3848 2258);
FORCEPROP 2 LAST CDS_LIB standard
J 0
(-3850 2250);
DISPLAY INVISIBLE (-3850 2250);
FORCEPROP 2 LAST ROOM RISER1
J 0
(-4350 2300);
DISPLAY 0.829787 (-4350 2300);
PAINT RED (-4350 2300);
DISPLAY INVISIBLE (-4350 2300);
FORCEPROP 2 LAST BOM_COST IO_SLOT
J 0
(-4350 2350);
DISPLAY 0.829787 (-4350 2350);
DISPLAY INVISIBLE (-4350 2350);
FORCEPROP 1 LAST BODY_TYPE PLUMBING
J 2
(-3850 2200);
DISPLAY 0.702128 (-3850 2200);
PAINT GREEN (-3850 2200);
DISPLAY INVISIBLE (-3850 2200);
FORCEPROP 1 LAST HDL_TAP TRUE
J 2
(-4175 2125);
DISPLAY 0.702128 (-4175 2125);
PAINT GREEN (-4175 2125);
DISPLAY INVISIBLE (-4175 2125);
FORCEPROP 1 LAST PATH I414
J 2
(-3848 2250);
DISPLAY 0.872340 (-3848 2250);
PAINT GREEN (-3848 2250);
DISPLAY INVISIBLE (-3848 2250);
FORCEADD TAP..6
R 2
(-3850 2050);
FORCEPROP 3 LASTPIN (-3900 2050) SIG_NAME P5E_CPU0_P3_TX_DP<10>
J 0
(-3890 2060);
DISPLAY 0.659574 (-3890 2060);
PAINT MONO (-3890 2060);
DISPLAY INVISIBLE (-3890 2060);
FORCEPROP 1 LASTPIN (-3900 2050) BN 10
J 2
(-3848 2058);
DISPLAY 0.680851 (-3848 2058);
PAINT MONO (-3848 2058);
FORCEPROP 2 LAST CDS_LIB standard
J 0
(-3850 2050);
DISPLAY INVISIBLE (-3850 2050);
FORCEPROP 2 LAST ROOM RISER1
J 0
(-4350 2100);
DISPLAY 0.829787 (-4350 2100);
PAINT RED (-4350 2100);
DISPLAY INVISIBLE (-4350 2100);
FORCEPROP 2 LAST BOM_COST IO_SLOT
J 0
(-4350 2150);
DISPLAY 0.829787 (-4350 2150);
DISPLAY INVISIBLE (-4350 2150);
FORCEPROP 1 LAST BODY_TYPE PLUMBING
J 2
(-3850 2000);
DISPLAY 0.702128 (-3850 2000);
PAINT GREEN (-3850 2000);
DISPLAY INVISIBLE (-3850 2000);
FORCEPROP 1 LAST HDL_TAP TRUE
J 2
(-4175 1925);
DISPLAY 0.702128 (-4175 1925);
PAINT GREEN (-4175 1925);
DISPLAY INVISIBLE (-4175 1925);
FORCEPROP 1 LAST PATH I415
J 2
(-3848 2050);
DISPLAY 0.872340 (-3848 2050);
PAINT GREEN (-3848 2050);
DISPLAY INVISIBLE (-3848 2050);
FORCEADD TAP..6
R 2
(-3850 2150);
FORCEPROP 3 LASTPIN (-3900 2150) SIG_NAME P5E_CPU0_P3_TX_DP<9>
J 0
(-3890 2160);
DISPLAY 0.659574 (-3890 2160);
PAINT MONO (-3890 2160);
DISPLAY INVISIBLE (-3890 2160);
FORCEPROP 1 LASTPIN (-3900 2150) BN 9
J 2
(-3848 2158);
DISPLAY 0.680851 (-3848 2158);
PAINT MONO (-3848 2158);
FORCEPROP 2 LAST CDS_LIB standard
J 0
(-3850 2150);
DISPLAY INVISIBLE (-3850 2150);
FORCEPROP 2 LAST ROOM RISER1
J 0
(-4350 2200);
DISPLAY 0.829787 (-4350 2200);
PAINT RED (-4350 2200);
DISPLAY INVISIBLE (-4350 2200);
FORCEPROP 2 LAST BOM_COST IO_SLOT
J 0
(-4350 2250);
DISPLAY 0.829787 (-4350 2250);
DISPLAY INVISIBLE (-4350 2250);
FORCEPROP 1 LAST BODY_TYPE PLUMBING
J 2
(-3850 2100);
DISPLAY 0.702128 (-3850 2100);
PAINT GREEN (-3850 2100);
DISPLAY INVISIBLE (-3850 2100);
FORCEPROP 1 LAST HDL_TAP TRUE
J 2
(-4175 2025);
DISPLAY 0.702128 (-4175 2025);
PAINT GREEN (-4175 2025);
DISPLAY INVISIBLE (-4175 2025);
FORCEPROP 1 LAST PATH I416
J 2
(-3848 2150);
DISPLAY 0.872340 (-3848 2150);
PAINT GREEN (-3848 2150);
DISPLAY INVISIBLE (-3848 2150);
FORCEADD TAP..6
R 2
(-3850 1950);
FORCEPROP 3 LASTPIN (-3900 1950) SIG_NAME P5E_CPU0_P3_TX_DP<11>
J 0
(-3890 1960);
DISPLAY 0.659574 (-3890 1960);
PAINT MONO (-3890 1960);
DISPLAY INVISIBLE (-3890 1960);
FORCEPROP 1 LASTPIN (-3900 1950) BN 11
J 2
(-3848 1958);
DISPLAY 0.680851 (-3848 1958);
PAINT MONO (-3848 1958);
FORCEPROP 2 LAST CDS_LIB standard
J 0
(-3850 1950);
DISPLAY INVISIBLE (-3850 1950);
FORCEPROP 2 LAST ROOM RISER1
J 0
(-4350 2000);
DISPLAY 0.829787 (-4350 2000);
PAINT RED (-4350 2000);
DISPLAY INVISIBLE (-4350 2000);
FORCEPROP 2 LAST BOM_COST IO_SLOT
J 0
(-4350 2050);
DISPLAY 0.829787 (-4350 2050);
DISPLAY INVISIBLE (-4350 2050);
FORCEPROP 1 LAST BODY_TYPE PLUMBING
J 2
(-3850 1900);
DISPLAY 0.702128 (-3850 1900);
PAINT GREEN (-3850 1900);
DISPLAY INVISIBLE (-3850 1900);
FORCEPROP 1 LAST HDL_TAP TRUE
J 2
(-4175 1825);
DISPLAY 0.702128 (-4175 1825);
PAINT GREEN (-4175 1825);
DISPLAY INVISIBLE (-4175 1825);
FORCEPROP 1 LAST PATH I417
J 2
(-3848 1950);
DISPLAY 0.872340 (-3848 1950);
PAINT GREEN (-3848 1950);
DISPLAY INVISIBLE (-3848 1950);
FORCEADD TAP..6
R 2
(-3850 1850);
FORCEPROP 3 LASTPIN (-3900 1850) SIG_NAME P5E_CPU0_P3_TX_DP<12>
J 0
(-3890 1860);
DISPLAY 0.659574 (-3890 1860);
PAINT MONO (-3890 1860);
DISPLAY INVISIBLE (-3890 1860);
FORCEPROP 1 LASTPIN (-3900 1850) BN 12
J 2
(-3848 1858);
DISPLAY 0.680851 (-3848 1858);
PAINT MONO (-3848 1858);
FORCEPROP 2 LAST CDS_LIB standard
J 0
(-3850 1850);
DISPLAY INVISIBLE (-3850 1850);
FORCEPROP 2 LAST ROOM RISER1
J 0
(-4350 1900);
DISPLAY 0.829787 (-4350 1900);
PAINT RED (-4350 1900);
DISPLAY INVISIBLE (-4350 1900);
FORCEPROP 2 LAST BOM_COST IO_SLOT
J 0
(-4350 1950);
DISPLAY 0.829787 (-4350 1950);
DISPLAY INVISIBLE (-4350 1950);
FORCEPROP 1 LAST BODY_TYPE PLUMBING
J 2
(-3850 1800);
DISPLAY 0.702128 (-3850 1800);
PAINT GREEN (-3850 1800);
DISPLAY INVISIBLE (-3850 1800);
FORCEPROP 1 LAST HDL_TAP TRUE
J 2
(-4175 1725);
DISPLAY 0.702128 (-4175 1725);
PAINT GREEN (-4175 1725);
DISPLAY INVISIBLE (-4175 1725);
FORCEPROP 1 LAST PATH I418
J 2
(-3848 1850);
DISPLAY 0.872340 (-3848 1850);
PAINT GREEN (-3848 1850);
DISPLAY INVISIBLE (-3848 1850);
FORCEADD TAP..6
R 2
(-3700 1600);
FORCEPROP 3 LASTPIN (-3750 1600) SIG_NAME P5E_CPU0_P3_TX_DN<14>
J 0
(-3740 1610);
DISPLAY 0.659574 (-3740 1610);
PAINT MONO (-3740 1610);
DISPLAY INVISIBLE (-3740 1610);
FORCEPROP 1 LASTPIN (-3750 1600) BN 14
J 2
(-3698 1608);
DISPLAY 0.680851 (-3698 1608);
PAINT MONO (-3698 1608);
FORCEPROP 2 LAST CDS_LIB standard
J 0
(-3700 1600);
DISPLAY INVISIBLE (-3700 1600);
FORCEPROP 2 LAST ROOM RISER1
J 0
(-4200 1650);
DISPLAY 0.829787 (-4200 1650);
PAINT RED (-4200 1650);
DISPLAY INVISIBLE (-4200 1650);
FORCEPROP 2 LAST BOM_COST IO_SLOT
J 0
(-4200 1700);
DISPLAY 0.829787 (-4200 1700);
DISPLAY INVISIBLE (-4200 1700);
FORCEPROP 1 LAST BODY_TYPE PLUMBING
J 2
(-3700 1550);
DISPLAY 0.702128 (-3700 1550);
PAINT GREEN (-3700 1550);
DISPLAY INVISIBLE (-3700 1550);
FORCEPROP 1 LAST HDL_TAP TRUE
J 2
(-4025 1475);
DISPLAY 0.702128 (-4025 1475);
PAINT GREEN (-4025 1475);
DISPLAY INVISIBLE (-4025 1475);
FORCEPROP 1 LAST PATH I419
J 2
(-3698 1600);
DISPLAY 0.872340 (-3698 1600);
PAINT GREEN (-3698 1600);
DISPLAY INVISIBLE (-3698 1600);
FORCEADD TAP..6
R 2
(-3700 1700);
FORCEPROP 3 LASTPIN (-3750 1700) SIG_NAME P5E_CPU0_P3_TX_DN<13>
J 0
(-3740 1710);
DISPLAY 0.659574 (-3740 1710);
PAINT MONO (-3740 1710);
DISPLAY INVISIBLE (-3740 1710);
FORCEPROP 1 LASTPIN (-3750 1700) BN 13
J 2
(-3698 1708);
DISPLAY 0.680851 (-3698 1708);
PAINT MONO (-3698 1708);
FORCEPROP 2 LAST CDS_LIB standard
J 0
(-3700 1700);
DISPLAY INVISIBLE (-3700 1700);
FORCEPROP 2 LAST ROOM RISER1
J 0
(-4200 1750);
DISPLAY 0.829787 (-4200 1750);
PAINT RED (-4200 1750);
DISPLAY INVISIBLE (-4200 1750);
FORCEPROP 2 LAST BOM_COST IO_SLOT
J 0
(-4200 1800);
DISPLAY 0.829787 (-4200 1800);
DISPLAY INVISIBLE (-4200 1800);
FORCEPROP 1 LAST BODY_TYPE PLUMBING
J 2
(-3700 1650);
DISPLAY 0.702128 (-3700 1650);
PAINT GREEN (-3700 1650);
DISPLAY INVISIBLE (-3700 1650);
FORCEPROP 1 LAST HDL_TAP TRUE
J 2
(-4025 1575);
DISPLAY 0.702128 (-4025 1575);
PAINT GREEN (-4025 1575);
DISPLAY INVISIBLE (-4025 1575);
FORCEPROP 1 LAST PATH I420
J 2
(-3698 1700);
DISPLAY 0.872340 (-3698 1700);
PAINT GREEN (-3698 1700);
DISPLAY INVISIBLE (-3698 1700);
FORCEADD TAP..6
R 2
(-3700 1500);
FORCEPROP 3 LASTPIN (-3750 1500) SIG_NAME P5E_CPU0_P3_TX_DN<15>
J 0
(-3740 1510);
DISPLAY 0.659574 (-3740 1510);
PAINT MONO (-3740 1510);
DISPLAY INVISIBLE (-3740 1510);
FORCEPROP 1 LASTPIN (-3750 1500) BN 15
J 2
(-3698 1508);
DISPLAY 0.680851 (-3698 1508);
PAINT MONO (-3698 1508);
FORCEPROP 2 LAST CDS_LIB standard
J 0
(-3700 1500);
DISPLAY INVISIBLE (-3700 1500);
FORCEPROP 2 LAST ROOM RISER1
J 0
(-4200 1550);
DISPLAY 0.829787 (-4200 1550);
PAINT RED (-4200 1550);
DISPLAY INVISIBLE (-4200 1550);
FORCEPROP 2 LAST BOM_COST IO_SLOT
J 0
(-4200 1600);
DISPLAY 0.829787 (-4200 1600);
DISPLAY INVISIBLE (-4200 1600);
FORCEPROP 1 LAST BODY_TYPE PLUMBING
J 2
(-3700 1450);
DISPLAY 0.702128 (-3700 1450);
PAINT GREEN (-3700 1450);
DISPLAY INVISIBLE (-3700 1450);
FORCEPROP 1 LAST HDL_TAP TRUE
J 2
(-4025 1375);
DISPLAY 0.702128 (-4025 1375);
PAINT GREEN (-4025 1375);
DISPLAY INVISIBLE (-4025 1375);
FORCEPROP 1 LAST PATH I421
J 2
(-3698 1500);
DISPLAY 0.872340 (-3698 1500);
PAINT GREEN (-3698 1500);
DISPLAY INVISIBLE (-3698 1500);
FORCEADD TAP..6
R 2
(-3850 1750);
FORCEPROP 3 LASTPIN (-3900 1750) SIG_NAME P5E_CPU0_P3_TX_DP<13>
J 0
(-3890 1760);
DISPLAY 0.659574 (-3890 1760);
PAINT MONO (-3890 1760);
DISPLAY INVISIBLE (-3890 1760);
FORCEPROP 1 LASTPIN (-3900 1750) BN 13
J 2
(-3848 1758);
DISPLAY 0.680851 (-3848 1758);
PAINT MONO (-3848 1758);
FORCEPROP 2 LAST CDS_LIB standard
J 0
(-3850 1750);
DISPLAY INVISIBLE (-3850 1750);
FORCEPROP 2 LAST ROOM RISER1
J 0
(-4350 1800);
DISPLAY 0.829787 (-4350 1800);
PAINT RED (-4350 1800);
DISPLAY INVISIBLE (-4350 1800);
FORCEPROP 2 LAST BOM_COST IO_SLOT
J 0
(-4350 1850);
DISPLAY 0.829787 (-4350 1850);
DISPLAY INVISIBLE (-4350 1850);
FORCEPROP 1 LAST BODY_TYPE PLUMBING
J 2
(-3850 1700);
DISPLAY 0.702128 (-3850 1700);
PAINT GREEN (-3850 1700);
DISPLAY INVISIBLE (-3850 1700);
FORCEPROP 1 LAST HDL_TAP TRUE
J 2
(-4175 1625);
DISPLAY 0.702128 (-4175 1625);
PAINT GREEN (-4175 1625);
DISPLAY INVISIBLE (-4175 1625);
FORCEPROP 1 LAST PATH I422
J 2
(-3848 1750);
DISPLAY 0.872340 (-3848 1750);
PAINT GREEN (-3848 1750);
DISPLAY INVISIBLE (-3848 1750);
FORCEADD TAP..6
R 2
(-3850 1550);
FORCEPROP 3 LASTPIN (-3900 1550) SIG_NAME P5E_CPU0_P3_TX_DP<15>
J 0
(-3890 1560);
DISPLAY 0.659574 (-3890 1560);
PAINT MONO (-3890 1560);
DISPLAY INVISIBLE (-3890 1560);
FORCEPROP 1 LASTPIN (-3900 1550) BN 15
J 2
(-3848 1558);
DISPLAY 0.680851 (-3848 1558);
PAINT MONO (-3848 1558);
FORCEPROP 2 LAST CDS_LIB standard
J 0
(-3850 1550);
DISPLAY INVISIBLE (-3850 1550);
FORCEPROP 2 LAST ROOM RISER1
J 0
(-4350 1600);
DISPLAY 0.829787 (-4350 1600);
PAINT RED (-4350 1600);
DISPLAY INVISIBLE (-4350 1600);
FORCEPROP 2 LAST BOM_COST IO_SLOT
J 0
(-4350 1650);
DISPLAY 0.829787 (-4350 1650);
DISPLAY INVISIBLE (-4350 1650);
FORCEPROP 1 LAST BODY_TYPE PLUMBING
J 2
(-3850 1500);
DISPLAY 0.702128 (-3850 1500);
PAINT GREEN (-3850 1500);
DISPLAY INVISIBLE (-3850 1500);
FORCEPROP 1 LAST HDL_TAP TRUE
J 2
(-4175 1425);
DISPLAY 0.702128 (-4175 1425);
PAINT GREEN (-4175 1425);
DISPLAY INVISIBLE (-4175 1425);
FORCEPROP 1 LAST PATH I423
J 2
(-3848 1550);
DISPLAY 0.872340 (-3848 1550);
PAINT GREEN (-3848 1550);
DISPLAY INVISIBLE (-3848 1550);
FORCEADD TAP..6
R 2
(-3850 1650);
FORCEPROP 3 LASTPIN (-3900 1650) SIG_NAME P5E_CPU0_P3_TX_DP<14>
J 0
(-3890 1660);
DISPLAY 0.659574 (-3890 1660);
PAINT MONO (-3890 1660);
DISPLAY INVISIBLE (-3890 1660);
FORCEPROP 1 LASTPIN (-3900 1650) BN 14
J 2
(-3848 1658);
DISPLAY 0.680851 (-3848 1658);
PAINT MONO (-3848 1658);
FORCEPROP 2 LAST CDS_LIB standard
J 0
(-3850 1650);
DISPLAY INVISIBLE (-3850 1650);
FORCEPROP 2 LAST ROOM RISER1
J 0
(-4350 1700);
DISPLAY 0.829787 (-4350 1700);
PAINT RED (-4350 1700);
DISPLAY INVISIBLE (-4350 1700);
FORCEPROP 2 LAST BOM_COST IO_SLOT
J 0
(-4350 1750);
DISPLAY 0.829787 (-4350 1750);
DISPLAY INVISIBLE (-4350 1750);
FORCEPROP 1 LAST BODY_TYPE PLUMBING
J 2
(-3850 1600);
DISPLAY 0.702128 (-3850 1600);
PAINT GREEN (-3850 1600);
DISPLAY INVISIBLE (-3850 1600);
FORCEPROP 1 LAST HDL_TAP TRUE
J 2
(-4175 1525);
DISPLAY 0.702128 (-4175 1525);
PAINT GREEN (-4175 1525);
DISPLAY INVISIBLE (-4175 1525);
FORCEPROP 1 LAST PATH I424
J 2
(-3848 1650);
DISPLAY 0.872340 (-3848 1650);
PAINT GREEN (-3848 1650);
DISPLAY INVISIBLE (-3848 1650);
FORCEADD OFFPAGE..2
(-2750 3225);
FORCEPROP 2 LAST $XR0 64 
J 0
(-2561 3225);
DISPLAY 0.638298 (-2561 3225);
PAINT MONO (-2561 3225);
FORCEPROP 2 LAST CDS_LIB standard
J 0
(-2750 3225);
DISPLAY INVISIBLE (-2750 3225);
FORCEPROP 1 LAST OFFPAGE TRUE
J 0
(-2425 3100);
DISPLAY 0.872340 (-2425 3100);
PAINT GREEN (-2425 3100);
DISPLAY INVISIBLE (-2425 3100);
FORCEPROP 1 LAST COMMENT_BODY TRUE
J 0
(-2795 3130);
DISPLAY 0.872340 (-2795 3130);
PAINT GREEN (-2795 3130);
DISPLAY INVISIBLE (-2795 3130);
FORCEPROP 2 LAST PATH I425
J 0
(-2575 3300);
DISPLAY 0.680851 (-2575 3300);
DISPLAY INVISIBLE (-2575 3300);
FORCEADD OFFPAGE..2
(-2750 3275);
FORCEPROP 2 LAST $XR0 64 
J 0
(-2561 3275);
DISPLAY 0.638298 (-2561 3275);
PAINT MONO (-2561 3275);
FORCEPROP 2 LAST CDS_LIB standard
J 0
(-2750 3275);
DISPLAY INVISIBLE (-2750 3275);
FORCEPROP 1 LAST OFFPAGE TRUE
J 0
(-2425 3150);
DISPLAY 0.872340 (-2425 3150);
PAINT GREEN (-2425 3150);
DISPLAY INVISIBLE (-2425 3150);
FORCEPROP 1 LAST COMMENT_BODY TRUE
J 0
(-2795 3180);
DISPLAY 0.872340 (-2795 3180);
PAINT GREEN (-2795 3180);
DISPLAY INVISIBLE (-2795 3180);
FORCEPROP 2 LAST PATH I426
J 0
(-2575 3350);
DISPLAY 0.680851 (-2575 3350);
DISPLAY INVISIBLE (-2575 3350);
FORCEADD QUANTA_TITLE_BLOCK_C..1
(-100 100);
FORCEPROP 0 LAST CDS_CON_LAST_MODIFIED Thu Sep 14 16:11:52 2023
J 0
(-1985 115);
DISPLAY INVISIBLE (-1985 115);
FORCEPROP 1 LAST CUSTOM_TXT_CDS <CON_LAST_MODIFIED>
J 0
(-1985 115);
DISPLAY 0.978723 (-1985 115);
FORCEPROP 2 LAST CUSTOM_TXT_CDS <XR_PAGE_TITLE>
J 0
(-7990 5350);
DISPLAY 0.638298 (-7990 5350);
PAINT PINK (-7990 5350);
DISPLAY INVISIBLE (-7990 5350);
FORCEPROP 1 LAST CUSTOM_TXT_CDS <NAME_2>
J 0
(-3275 150);
FORCEPROP 1 LAST CUSTOM_TXT_CDS <NAME_1>
J 0
(-3275 275);
FORCEPROP 1 LAST CUSTOM_TXT_CDS <Q_NUMBER>
J 0
(-1503 203);
DISPLAY 1.212766 (-1503 203);
FORCEPROP 1 LAST CUSTOM_TXT_CDS <Q_PROJ>
J 0
(-2482 202);
DISPLAY 1.212766 (-2482 202);
FORCEPROP 1 LAST CUSTOM_TXT_CDS <Q_REV>
J 0
(-284 203);
DISPLAY 1.212766 (-284 203);
FORCEPROP 1 LAST CUSTOM_TXT_CDS <CON_PAGE_NUM> OF <CON_TOTAL_PAGES>
J 0
(-546 118);
DISPLAY 0.978723 (-546 118);
FORCEPROP 1 LAST Q_TITLE CPU0 PCIE P2/P3
J 0
(-9425 150);
DISPLAY 2.446809 (-9425 150);
PAINT GREEN (-9425 150);
FORCEPROP 2 LAST PAGE_BORDER TRUE
J 0
(-7990 5350);
DISPLAY 0.638298 (-7990 5350);
PAINT PINK (-7990 5350);
DISPLAY INVISIBLE (-7990 5350);
FORCEPROP 1 LAST CDS_LMAN_SYM_OUTLINE -9475,6775,100,-125
J 0
(-100 100);
DISPLAY 0.468085 (-100 100);
PAINT GREEN (-100 100);
DISPLAY INVISIBLE (-100 100);
FORCEPROP 2 LAST CDS_LIB pure_quanta
J 0
(-100 100);
DISPLAY INVISIBLE (-100 100);
FORCEPROP 2 LAST CDS_XR_PAGE_TITLE CR-25 : @T6G_MB_LIB.T6G(SCH_1):PAGE25
J 0
(-7990 5350);
DISPLAY 0.638298 (-7990 5350);
PAINT PINK (-7990 5350);
DISPLAY INVISIBLE (-7990 5350);
FORCEPROP 1 LAST Q_DEPT BU9
J 1
(-3863 149);
DISPLAY 1.957447 (-3863 149);
PAINT GREEN (-3863 149);
DISPLAY INVISIBLE (-3863 149);
FORCEPROP 1 LAST COMMENT_BODY TRUE
J 0
(-88 87);
DISPLAY 0.978723 (-88 87);
PAINT GREEN (-88 87);
DISPLAY INVISIBLE (-88 87);
WIRE 17 -1 (-3650 2925)(-3650 2825);
WIRE 17 -1 (-3650 3025)(-3650 2925);
WIRE 17 -1 (-3650 2825)(-3650 2725);
WIRE 17 -1 (-3650 2725)(-3650 2625);
WIRE 17 -1 (-3650 3225)(-3650 3025);
WIRE 17 -1 (-3650 3225)(-2800 3225);
FORCEPROP 2 LAST SIG_NAME P5E_CPU0_P3_TX_DN<15:0>
J 0
(-3485 3235);
DISPLAY 0.489362 (-3485 3235);
WIRE 17 -1 (-3800 2975)(-3800 2875);
WIRE 17 -1 (-3800 3075)(-3800 2975);
WIRE 17 -1 (-3800 2875)(-3800 2775);
WIRE 17 -1 (-3800 2775)(-3800 2675);
WIRE 17 -1 (-3800 3275)(-3800 3075);
WIRE 17 -1 (-3800 3275)(-2800 3275);
FORCEPROP 2 LAST SIG_NAME P5E_CPU0_P3_TX_DP<15:0>
J 0
(-3485 3310);
DISPLAY 0.489362 (-3485 3310);
WIRE 17 -1 (-6350 2875)(-6350 2975);
WIRE 17 -1 (-6350 2775)(-6350 2875);
WIRE 17 -1 (-6350 2975)(-6350 3075);
WIRE 17 -1 (-6350 3075)(-6350 3275);
WIRE 17 -1 (-6350 2675)(-6350 2775);
WIRE 17 -1 (-6350 2575)(-6350 2675);
WIRE 17 -1 (-6350 3275)(-7425 3275);
FORCEPROP 2 LAST SIG_NAME P5E_CPU0_P3_RX_DP<15:0>
J 0
(-7360 3310);
DISPLAY 0.489362 (-7360 3310);
WIRE 17 -1 (-6500 2925)(-6500 3025);
WIRE 17 -1 (-6500 2825)(-6500 2925);
WIRE 17 -1 (-6500 3025)(-6500 3225);
WIRE 17 -1 (-6500 3225)(-7425 3225);
FORCEPROP 2 LAST SIG_NAME P5E_CPU0_P3_RX_DN<15:0>
J 0
(-7385 3235);
DISPLAY 0.489362 (-7385 3235);
WIRE 17 -1 (-3650 2625)(-3650 2525);
WIRE 17 -1 (-3650 2525)(-3650 2425);
WIRE 17 -1 (-3650 2425)(-3650 2325);
WIRE 17 -1 (-3650 2325)(-3650 2225);
WIRE 17 -1 (-3800 2675)(-3800 2575);
WIRE 17 -1 (-3800 2575)(-3800 2475);
WIRE 17 -1 (-3800 2475)(-3800 2375);
WIRE 17 -1 (-3800 2375)(-3800 2275);
WIRE 17 -1 (-3800 2275)(-3800 2175);
WIRE 17 -1 (-3800 2175)(-3800 2075);
WIRE 17 -1 (-3800 2075)(-3800 1975);
WIRE 17 -1 (-3800 1975)(-3800 1875);
WIRE 17 -1 (-3800 1875)(-3800 1775);
WIRE 17 -1 (-3800 1775)(-3800 1675);
WIRE 17 -1 (-3800 1675)(-3800 1575);
WIRE 17 -1 (-6350 4400)(-6350 4500);
WIRE 17 -1 (-6350 4500)(-6350 4600);
WIRE 17 -1 (-6350 4600)(-6350 4700);
WIRE 17 -1 (-6350 4700)(-6350 4800);
WIRE 17 -1 (-6350 4800)(-6350 4900);
WIRE 17 -1 (-6350 4900)(-6350 5000);
WIRE 17 -1 (-6350 5000)(-6350 5100);
WIRE 17 -1 (-6350 5100)(-6350 5200);
WIRE 17 -1 (-6350 5200)(-6350 5300);
WIRE 17 -1 (-6350 5300)(-6350 5400);
WIRE 17 -1 (-6350 5400)(-6350 5500);
WIRE 17 -1 (-6350 5500)(-6350 5600);
WIRE 17 -1 (-6350 5600)(-6350 5700);
WIRE 17 -1 (-6350 5700)(-6350 5800);
WIRE 17 -1 (-6350 5800)(-6350 5900);
WIRE 17 -1 (-6350 5900)(-6350 6100);
WIRE 17 -1 (-6350 6100)(-7425 6100);
FORCEPROP 2 LAST SIG_NAME P5E_CPU0_P2_RX_DP<15:0>
J 0
(-7200 6110);
DISPLAY 0.489362 (-7200 6110);
WIRE 17 -1 (-6500 2725)(-6500 2825);
WIRE 17 -1 (-6500 2625)(-6500 2725);
WIRE 17 -1 (-6500 2525)(-6500 2625);
WIRE 17 -1 (-6500 2425)(-6500 2525);
WIRE 17 -1 (-3650 2225)(-3650 2125);
WIRE 17 -1 (-3650 2125)(-3650 2025);
WIRE 17 -1 (-3650 2025)(-3650 1925);
WIRE 17 -1 (-3650 1925)(-3650 1825);
WIRE 17 -1 (-3650 1825)(-3650 1725);
WIRE 17 -1 (-3650 1725)(-3650 1625);
WIRE 17 -1 (-3650 1625)(-3650 1525);
WIRE 17 -1 (-6500 1625)(-6500 1725);
WIRE 17 -1 (-6500 1525)(-6500 1625);
WIRE 17 -1 (-6500 1725)(-6500 1825);
WIRE 17 -1 (-6500 1825)(-6500 1925);
WIRE 17 -1 (-6500 1925)(-6500 2025);
WIRE 17 -1 (-6500 2025)(-6500 2125);
WIRE 17 -1 (-6500 2125)(-6500 2225);
WIRE 17 -1 (-6500 2225)(-6500 2325);
WIRE 17 -1 (-6500 2325)(-6500 2425);
WIRE 17 -1 (-6350 1975)(-6350 2075);
WIRE 17 -1 (-6350 1875)(-6350 1975);
WIRE 17 -1 (-6350 2075)(-6350 2175);
WIRE 17 -1 (-6350 2175)(-6350 2275);
WIRE 17 -1 (-6350 1775)(-6350 1875);
WIRE 17 -1 (-6350 1675)(-6350 1775);
WIRE 17 -1 (-6350 2275)(-6350 2375);
WIRE 17 -1 (-6350 2375)(-6350 2475);
WIRE 17 -1 (-6350 1575)(-6350 1675);
WIRE 17 -1 (-6350 2475)(-6350 2575);
WIRE 17 -1 (-6500 4350)(-6500 4450);
WIRE 17 -1 (-6500 4450)(-6500 4550);
WIRE 17 -1 (-6500 4550)(-6500 4650);
WIRE 17 -1 (-6500 4650)(-6500 4750);
WIRE 17 -1 (-6500 4750)(-6500 4850);
WIRE 17 -1 (-6500 4850)(-6500 4950);
WIRE 17 -1 (-6500 4950)(-6500 5050);
WIRE 17 -1 (-6500 5050)(-6500 5150);
WIRE 17 -1 (-6500 5150)(-6500 5250);
WIRE 17 -1 (-6500 5250)(-6500 5350);
WIRE 17 -1 (-6500 5350)(-6500 5450);
WIRE 17 -1 (-6500 5450)(-6500 5550);
WIRE 17 -1 (-6500 5550)(-6500 5650);
WIRE 17 -1 (-6500 5650)(-6500 5750);
WIRE 17 -1 (-6500 5750)(-6500 5850);
WIRE 17 -1 (-6500 5850)(-6500 6050);
WIRE 17 -1 (-6500 6050)(-7425 6050);
FORCEPROP 2 LAST SIG_NAME P5E_CPU0_P2_RX_DN<15:0>
J 0
(-7200 6060);
DISPLAY 0.489362 (-7200 6060);
WIRE 17 -1 (-3650 4450)(-3650 4350);
WIRE 17 -1 (-3650 4550)(-3650 4450);
WIRE 17 -1 (-3650 4650)(-3650 4550);
WIRE 17 -1 (-3650 4750)(-3650 4650);
WIRE 17 -1 (-3650 4850)(-3650 4750);
WIRE 17 -1 (-3650 4950)(-3650 4850);
WIRE 17 -1 (-3650 5050)(-3650 4950);
WIRE 17 -1 (-3650 5150)(-3650 5050);
WIRE 17 -1 (-3650 5250)(-3650 5150);
WIRE 17 -1 (-3650 5350)(-3650 5250);
WIRE 17 -1 (-3650 5450)(-3650 5350);
WIRE 17 -1 (-3650 5550)(-3650 5450);
WIRE 17 -1 (-3650 5650)(-3650 5550);
WIRE 17 -1 (-3650 5750)(-3650 5650);
WIRE 17 -1 (-3650 5850)(-3650 5750);
WIRE 17 -1 (-3650 6025)(-3650 5850);
WIRE 17 -1 (-3650 6025)(-3025 6025);
FORCEPROP 2 LAST SIG_NAME P5E_CPU0_P2_TX_DN<15:0>
J 0
(-3510 6035);
DISPLAY 0.489362 (-3510 6035);
WIRE 17 -1 (-3800 5200)(-3800 5100);
WIRE 17 -1 (-3800 5300)(-3800 5200);
WIRE 17 -1 (-3800 5100)(-3800 5000);
WIRE 17 -1 (-3800 5000)(-3800 4900);
WIRE 17 -1 (-3800 5400)(-3800 5300);
WIRE 17 -1 (-3800 5500)(-3800 5400);
WIRE 17 -1 (-3800 4900)(-3800 4800);
WIRE 17 -1 (-3800 4800)(-3800 4700);
WIRE 17 -1 (-3800 5600)(-3800 5500);
WIRE 17 -1 (-3800 5700)(-3800 5600);
WIRE 17 -1 (-3800 4700)(-3800 4600);
WIRE 17 -1 (-3800 4600)(-3800 4500);
WIRE 17 -1 (-3800 5800)(-3800 5700);
WIRE 17 -1 (-3800 5900)(-3800 5800);
WIRE 17 -1 (-3800 4500)(-3800 4400);
WIRE 17 -1 (-3800 6075)(-3800 5900);
WIRE 17 -1 (-3800 6075)(-3025 6075);
FORCEPROP 2 LAST SIG_NAME P5E_CPU0_P2_TX_DP<15:0>
J 0
(-3510 6085);
DISPLAY 0.489362 (-3510 6085);
WIRE 16 -1 (-6400 5625)(-5775 5625);
WIRE 16 -1 (-6250 5575)(-5775 5575);
WIRE 16 -1 (-4275 5425)(-3750 5425);
WIRE 16 -1 (-4275 5475)(-3900 5475);
WIRE 16 -1 (-4275 2100)(-3750 2100);
WIRE 16 -1 (-4275 2150)(-3900 2150);
WIRE 16 -1 (-4275 2200)(-3750 2200);
WIRE 16 -1 (-4275 2300)(-3750 2300);
WIRE 16 -1 (-4275 2950)(-3900 2950);
WIRE 16 -1 (-4275 3000)(-3750 3000);
WIRE 16 -1 (-6400 2800)(-5775 2800);
WIRE 16 -1 (-6250 2750)(-5775 2750);
WIRE 16 -1 (-6250 2850)(-5775 2850);
WIRE 16 -1 (-6400 4525)(-5775 4525);
WIRE 16 -1 (-6250 4575)(-5775 4575);
WIRE 16 -1 (-6400 4625)(-5775 4625);
WIRE 16 -1 (-6400 5125)(-5775 5125);
WIRE 16 -1 (-6400 5225)(-5775 5225);
WIRE 16 -1 (-6400 5325)(-5775 5325);
WIRE 16 -1 (-6250 5175)(-5775 5175);
WIRE 16 -1 (-6400 5425)(-5775 5425);
WIRE 16 -1 (-6250 5275)(-5775 5275);
WIRE 16 -1 (-6400 5525)(-5775 5525);
WIRE 16 -1 (-6250 5375)(-5775 5375);
WIRE 16 -1 (-6250 5475)(-5775 5475);
WIRE 16 -1 (-6400 5725)(-5775 5725);
WIRE 16 -1 (-6400 5825)(-5775 5825);
WIRE 16 -1 (-6250 5675)(-5775 5675);
WIRE 16 -1 (-6250 5775)(-5775 5775);
WIRE 16 -1 (-6250 5875)(-5775 5875);
WIRE 16 -1 (-6400 4425)(-5775 4425);
WIRE 16 -1 (-6250 4675)(-5775 4675);
WIRE 16 -1 (-6400 4725)(-5775 4725);
WIRE 16 -1 (-6250 4775)(-5775 4775);
WIRE 16 -1 (-6400 4825)(-5775 4825);
WIRE 16 -1 (-6250 4875)(-5775 4875);
WIRE 16 -1 (-6400 4925)(-5775 4925);
WIRE 16 -1 (-6250 4975)(-5775 4975);
WIRE 16 -1 (-6400 5025)(-5775 5025);
WIRE 16 -1 (-6250 5075)(-5775 5075);
WIRE 16 -1 (-4275 5125)(-3750 5125);
WIRE 16 -1 (-4275 5225)(-3750 5225);
WIRE 16 -1 (-4275 5325)(-3750 5325);
WIRE 16 -1 (-4275 5175)(-3900 5175);
WIRE 16 -1 (-4275 5275)(-3900 5275);
WIRE 16 -1 (-4275 5525)(-3750 5525);
WIRE 16 -1 (-4275 5375)(-3900 5375);
WIRE 16 -1 (-4275 5625)(-3750 5625);
WIRE 16 -1 (-4275 5725)(-3750 5725);
WIRE 16 -1 (-4275 5575)(-3900 5575);
WIRE 16 -1 (-4275 5825)(-3750 5825);
WIRE 16 -1 (-4275 5675)(-3900 5675);
WIRE 16 -1 (-4275 5775)(-3900 5775);
WIRE 16 -1 (-4275 5875)(-3900 5875);
WIRE 16 -1 (-4275 4375)(-3900 4375);
WIRE 16 -1 (-4275 4425)(-3750 4425);
WIRE 16 -1 (-4275 4475)(-3900 4475);
WIRE 16 -1 (-4275 4525)(-3750 4525);
WIRE 16 -1 (-4275 4575)(-3900 4575);
WIRE 16 -1 (-4275 4625)(-3750 4625);
WIRE 16 -1 (-4275 4675)(-3900 4675);
WIRE 16 -1 (-4275 4725)(-3750 4725);
WIRE 16 -1 (-4275 4775)(-3900 4775);
WIRE 16 -1 (-4275 4825)(-3750 4825);
WIRE 16 -1 (-4275 4875)(-3900 4875);
WIRE 16 -1 (-4275 4925)(-3750 4925);
WIRE 16 -1 (-4275 4975)(-3900 4975);
WIRE 16 -1 (-4275 5025)(-3750 5025);
WIRE 16 -1 (-4275 5075)(-3900 5075);
WIRE 16 -1 (-4275 4325)(-3750 4325);
WIRE 16 -1 (-6400 4325)(-5775 4325);
WIRE 16 -1 (-6250 4475)(-5775 4475);
WIRE 16 -1 (-4275 1900)(-3750 1900);
WIRE 16 -1 (-4275 1950)(-3900 1950);
WIRE 16 -1 (-4275 2050)(-3900 2050);
WIRE 16 -1 (-4275 2500)(-3750 2500);
WIRE 16 -1 (-4275 2550)(-3900 2550);
WIRE 16 -1 (-6400 1500)(-5775 1500);
WIRE 16 -1 (-6250 1550)(-5775 1550);
WIRE 16 -1 (-6250 1650)(-5775 1650);
WIRE 16 -1 (-6400 1700)(-5775 1700);
WIRE 16 -1 (-6250 1750)(-5775 1750);
WIRE 16 -1 (-6250 1850)(-5775 1850);
WIRE 16 -1 (-6250 2050)(-5775 2050);
WIRE 16 -1 (-6250 2150)(-5775 2150);
WIRE 16 -1 (-6250 2250)(-5775 2250);
WIRE 16 -1 (-6400 2300)(-5775 2300);
WIRE 16 -1 (-6250 2450)(-5775 2450);
WIRE 16 -1 (-6400 2500)(-5775 2500);
WIRE 16 -1 (-6250 2550)(-5775 2550);
WIRE 16 -1 (-6400 2900)(-5775 2900);
WIRE 16 -1 (-6250 3050)(-5775 3050);
WIRE 16 -1 (-6400 2600)(-5775 2600);
WIRE 16 -1 (-6250 2650)(-5775 2650);
WIRE 16 -1 (-6400 2400)(-5775 2400);
WIRE 16 -1 (-6250 2350)(-5775 2350);
WIRE 16 -1 (-6400 2200)(-5775 2200);
WIRE 16 -1 (-6400 2100)(-5775 2100);
WIRE 16 -1 (-6400 2000)(-5775 2000);
WIRE 16 -1 (-6400 1900)(-5775 1900);
WIRE 16 -1 (-4275 1850)(-3900 1850);
WIRE 16 -1 (-4275 2000)(-3750 2000);
WIRE 16 -1 (-6250 1950)(-5775 1950);
WIRE 16 -1 (-6400 1800)(-5775 1800);
WIRE 16 -1 (-6400 1600)(-5775 1600);
WIRE 16 -1 (-4275 1500)(-3750 1500);
WIRE 16 -1 (-4275 1550)(-3900 1550);
WIRE 16 -1 (-4275 1600)(-3750 1600);
WIRE 16 -1 (-4275 1650)(-3900 1650);
WIRE 16 -1 (-4275 1700)(-3750 1700);
WIRE 16 -1 (-4275 1750)(-3900 1750);
WIRE 16 -1 (-4275 1800)(-3750 1800);
WIRE 16 -1 (-4275 2400)(-3750 2400);
WIRE 16 -1 (-4275 2450)(-3900 2450);
WIRE 16 -1 (-6400 2700)(-5775 2700);
WIRE 16 -1 (-6250 4375)(-5775 4375);
WIRE 16 -1 (-4275 2250)(-3900 2250);
WIRE 16 -1 (-4275 2350)(-3900 2350);
WIRE 16 -1 (-4275 3050)(-3900 3050);
WIRE 16 -1 (-4275 2900)(-3750 2900);
WIRE 16 -1 (-4275 2750)(-3900 2750);
WIRE 16 -1 (-4275 2700)(-3750 2700);
WIRE 16 -1 (-4275 2650)(-3900 2650);
WIRE 16 -1 (-4275 2600)(-3750 2600);
WIRE 16 -1 (-6400 3000)(-5775 3000);
WIRE 16 -1 (-6250 2950)(-5775 2950);
WIRE 16 -1 (-4275 2850)(-3900 2850);
WIRE 16 -1 (-4275 2800)(-3750 2800);
FORCENOTE
CPU0 P3[15:0] TO EXAMAX
(-2825 2175) 0;
DISPLAY LEFT (-2825 2175);
DISPLAY 2.000000 (-2825 2175);
FORCENOTE
CPU0 P2[15:0] TO EXAMAX
(-3025 5075) 0;
DISPLAY LEFT (-3025 5075);
DISPLAY 2.000000 (-3025 5075);
QUIT
